FILE_TYPE = MACRO_DRAWING;
SET COLOR_WIRE YELLOW;
SET COLOR_PROP ORANGE;
SET COLOR_DOT WHITE;
SET COLOR_ARC YELLOW;
SET COLOR_BODY GREEN;
SET COLOR_NOTE PURPLE;
SET PROP_DISPLAY VALUE;
SET PAGE_NUMBER P150;
FORCEADD UNIVERSAL_GND..1
(-4325 1500);
FORCEPROP 3 LASTPIN (-4325 1550) SIG_NAME GND\g
J 0
(-4315 1560);
DISPLAY 0.659574 (-4315 1560);
PAINT MONO (-4315 1560);
DISPLAY INVISIBLE (-4315 1560);
FORCEPROP 2 LAST CDS_LIB logical_power
J 0
(-4325 1500);
PAINT MONO (-4325 1500);
DISPLAY INVISIBLE (-4325 1500);
FORCEPROP 1 LAST HDL_POWER GND
J 1
(-4300 1425);
DISPLAY 0.872340 (-4300 1425);
PAINT GREEN (-4300 1425);
DISPLAY INVISIBLE (-4300 1425);
FORCEPROP 1 LAST PATH I1
J 0
(-4250 1500);
DISPLAY 0.872340 (-4250 1500);
PAINT AQUA (-4250 1500);
DISPLAY INVISIBLE (-4250 1500);
FORCEPROP 2 LAST ROOM IO_SLOT
J 1
(-4550 1575);
DISPLAY 0.744681 (-4550 1575);
DISPLAY INVISIBLE (-4550 1575);
FORCEADD OFFPAGE..5
(-2800 2650);
FORCEPROP 2 LAST $XR1 165 
J 0
(-3205 2650);
DISPLAY 0.638298 (-3205 2650);
PAINT MONO (-3205 2650);
FORCEPROP 2 LAST $XR0 156 
J 0
(-3085 2650);
DISPLAY 0.638298 (-3085 2650);
PAINT MONO (-3085 2650);
FORCEPROP 2 LAST CDS_LIB standard
J 0
(-2800 2650);
PAINT MONO (-2800 2650);
DISPLAY INVISIBLE (-2800 2650);
FORCEPROP 1 LAST OFFPAGE TRUE
J 0
(-2475 2525);
DISPLAY 0.872340 (-2475 2525);
PAINT GREEN (-2475 2525);
DISPLAY INVISIBLE (-2475 2525);
FORCEPROP 1 LAST COMMENT_BODY TRUE
J 0
(-2700 2575);
DISPLAY 0.872340 (-2700 2575);
PAINT GREEN (-2700 2575);
DISPLAY INVISIBLE (-2700 2575);
FORCEPROP 2 LAST PATH I10
J 0
(-3100 2700);
DISPLAY 1.021277 (-3100 2700);
DISPLAY INVISIBLE (-3100 2700);
FORCEADD TAP..1
(750 3450);
FORCEPROP 3 LASTPIN (700 3450) SIG_NAME P5E_CPU0_PE1_RX_DN<11>
J 0
(710 3460);
DISPLAY 0.659574 (710 3460);
PAINT MONO (710 3460);
DISPLAY INVISIBLE (710 3460);
FORCEPROP 1 LASTPIN (700 3450) BN 11
J 0
(688 3458);
DISPLAY 0.680851 (688 3458);
PAINT GREEN (688 3458);
FORCEPROP 2 LAST CDS_LIB standard
J 0
(750 3450);
PAINT MONO (750 3450);
DISPLAY INVISIBLE (750 3450);
FORCEPROP 1 LAST BODY_TYPE PLUMBING
J 0
(750 3500);
DISPLAY 0.872340 (750 3500);
PAINT GREEN (750 3500);
DISPLAY INVISIBLE (750 3500);
FORCEPROP 1 LAST HDL_TAP TRUE
J 0
(1075 3325);
DISPLAY 0.872340 (1075 3325);
PAINT GREEN (1075 3325);
DISPLAY INVISIBLE (1075 3325);
FORCEPROP 1 LAST PATH I100
J 0
(748 3450);
DISPLAY 0.872340 (748 3450);
PAINT GREEN (748 3450);
DISPLAY INVISIBLE (748 3450);
FORCEADD TAP..1
(750 3600);
FORCEPROP 3 LASTPIN (700 3600) SIG_NAME P5E_CPU0_PE1_RX_DN<10>
J 0
(710 3610);
DISPLAY 0.659574 (710 3610);
PAINT MONO (710 3610);
DISPLAY INVISIBLE (710 3610);
FORCEPROP 1 LASTPIN (700 3600) BN 10
J 0
(688 3608);
DISPLAY 0.680851 (688 3608);
PAINT GREEN (688 3608);
FORCEPROP 2 LAST CDS_LIB standard
J 0
(750 3600);
PAINT MONO (750 3600);
DISPLAY INVISIBLE (750 3600);
FORCEPROP 1 LAST BODY_TYPE PLUMBING
J 0
(750 3650);
DISPLAY 0.872340 (750 3650);
PAINT GREEN (750 3650);
DISPLAY INVISIBLE (750 3650);
FORCEPROP 1 LAST HDL_TAP TRUE
J 0
(1075 3475);
DISPLAY 0.872340 (1075 3475);
PAINT GREEN (1075 3475);
DISPLAY INVISIBLE (1075 3475);
FORCEPROP 1 LAST PATH I101
J 0
(748 3600);
DISPLAY 0.872340 (748 3600);
PAINT GREEN (748 3600);
DISPLAY INVISIBLE (748 3600);
FORCEADD TAP..1
(750 3750);
FORCEPROP 3 LASTPIN (700 3750) SIG_NAME P5E_CPU0_PE1_RX_DN<9>
J 0
(710 3760);
DISPLAY 0.659574 (710 3760);
PAINT MONO (710 3760);
DISPLAY INVISIBLE (710 3760);
FORCEPROP 1 LASTPIN (700 3750) BN 9
J 0
(688 3758);
DISPLAY 0.680851 (688 3758);
PAINT GREEN (688 3758);
FORCEPROP 2 LAST CDS_LIB standard
J 0
(750 3750);
PAINT MONO (750 3750);
DISPLAY INVISIBLE (750 3750);
FORCEPROP 1 LAST BODY_TYPE PLUMBING
J 0
(750 3800);
DISPLAY 0.872340 (750 3800);
PAINT GREEN (750 3800);
DISPLAY INVISIBLE (750 3800);
FORCEPROP 1 LAST HDL_TAP TRUE
J 0
(1075 3625);
DISPLAY 0.872340 (1075 3625);
PAINT GREEN (1075 3625);
DISPLAY INVISIBLE (1075 3625);
FORCEPROP 1 LAST PATH I102
J 0
(748 3750);
DISPLAY 0.872340 (748 3750);
PAINT GREEN (748 3750);
DISPLAY INVISIBLE (748 3750);
FORCEADD TAP..1
(750 3900);
FORCEPROP 3 LASTPIN (700 3900) SIG_NAME P5E_CPU0_PE1_RX_DN<8>
J 0
(710 3910);
DISPLAY 0.659574 (710 3910);
PAINT MONO (710 3910);
DISPLAY INVISIBLE (710 3910);
FORCEPROP 1 LASTPIN (700 3900) BN 8
J 0
(688 3908);
DISPLAY 0.680851 (688 3908);
PAINT GREEN (688 3908);
FORCEPROP 2 LAST CDS_LIB standard
J 0
(750 3900);
PAINT MONO (750 3900);
DISPLAY INVISIBLE (750 3900);
FORCEPROP 1 LAST BODY_TYPE PLUMBING
J 0
(750 3950);
DISPLAY 0.872340 (750 3950);
PAINT GREEN (750 3950);
DISPLAY INVISIBLE (750 3950);
FORCEPROP 1 LAST HDL_TAP TRUE
J 0
(1075 3775);
DISPLAY 0.872340 (1075 3775);
PAINT GREEN (1075 3775);
DISPLAY INVISIBLE (1075 3775);
FORCEPROP 1 LAST PATH I103
J 0
(748 3900);
DISPLAY 0.872340 (748 3900);
PAINT GREEN (748 3900);
DISPLAY INVISIBLE (748 3900);
FORCEADD TAP..1
(900 3050);
FORCEPROP 3 LASTPIN (850 3050) SIG_NAME P5E_CPU0_PE1_RX_DP<14>
J 0
(860 3060);
DISPLAY 0.659574 (860 3060);
PAINT MONO (860 3060);
DISPLAY INVISIBLE (860 3060);
FORCEPROP 1 LASTPIN (850 3050) BN 14
J 0
(838 3058);
DISPLAY 0.680851 (838 3058);
PAINT GREEN (838 3058);
FORCEPROP 2 LAST CDS_LIB standard
J 0
(900 3050);
PAINT MONO (900 3050);
DISPLAY INVISIBLE (900 3050);
FORCEPROP 1 LAST BODY_TYPE PLUMBING
J 0
(900 3100);
DISPLAY 0.872340 (900 3100);
PAINT GREEN (900 3100);
DISPLAY INVISIBLE (900 3100);
FORCEPROP 1 LAST HDL_TAP TRUE
J 0
(1225 2925);
DISPLAY 0.872340 (1225 2925);
PAINT GREEN (1225 2925);
DISPLAY INVISIBLE (1225 2925);
FORCEPROP 1 LAST PATH I104
J 0
(898 3050);
DISPLAY 0.872340 (898 3050);
PAINT GREEN (898 3050);
DISPLAY INVISIBLE (898 3050);
FORCEADD TAP..1
(900 3350);
FORCEPROP 3 LASTPIN (850 3350) SIG_NAME P5E_CPU0_PE1_RX_DP<12>
J 0
(860 3360);
DISPLAY 0.659574 (860 3360);
PAINT MONO (860 3360);
DISPLAY INVISIBLE (860 3360);
FORCEPROP 1 LASTPIN (850 3350) BN 12
J 0
(838 3358);
DISPLAY 0.680851 (838 3358);
PAINT GREEN (838 3358);
FORCEPROP 2 LAST CDS_LIB standard
J 0
(900 3350);
PAINT MONO (900 3350);
DISPLAY INVISIBLE (900 3350);
FORCEPROP 1 LAST BODY_TYPE PLUMBING
J 0
(900 3400);
DISPLAY 0.872340 (900 3400);
PAINT GREEN (900 3400);
DISPLAY INVISIBLE (900 3400);
FORCEPROP 1 LAST HDL_TAP TRUE
J 0
(1225 3225);
DISPLAY 0.872340 (1225 3225);
PAINT GREEN (1225 3225);
DISPLAY INVISIBLE (1225 3225);
FORCEPROP 1 LAST PATH I105
J 0
(898 3350);
DISPLAY 0.872340 (898 3350);
PAINT GREEN (898 3350);
DISPLAY INVISIBLE (898 3350);
FORCEADD TAP..1
(900 3200);
FORCEPROP 3 LASTPIN (850 3200) SIG_NAME P5E_CPU0_PE1_RX_DP<13>
J 0
(860 3210);
DISPLAY 0.659574 (860 3210);
PAINT MONO (860 3210);
DISPLAY INVISIBLE (860 3210);
FORCEPROP 1 LASTPIN (850 3200) BN 13
J 0
(838 3208);
DISPLAY 0.680851 (838 3208);
PAINT GREEN (838 3208);
FORCEPROP 2 LAST CDS_LIB standard
J 0
(900 3200);
PAINT MONO (900 3200);
DISPLAY INVISIBLE (900 3200);
FORCEPROP 1 LAST BODY_TYPE PLUMBING
J 0
(900 3250);
DISPLAY 0.872340 (900 3250);
PAINT GREEN (900 3250);
DISPLAY INVISIBLE (900 3250);
FORCEPROP 1 LAST HDL_TAP TRUE
J 0
(1225 3075);
DISPLAY 0.872340 (1225 3075);
PAINT GREEN (1225 3075);
DISPLAY INVISIBLE (1225 3075);
FORCEPROP 1 LAST PATH I106
J 0
(898 3200);
DISPLAY 0.872340 (898 3200);
PAINT GREEN (898 3200);
DISPLAY INVISIBLE (898 3200);
FORCEADD TAP..1
(900 3650);
FORCEPROP 3 LASTPIN (850 3650) SIG_NAME P5E_CPU0_PE1_RX_DP<10>
J 0
(860 3660);
DISPLAY 0.659574 (860 3660);
PAINT MONO (860 3660);
DISPLAY INVISIBLE (860 3660);
FORCEPROP 1 LASTPIN (850 3650) BN 10
J 0
(838 3658);
DISPLAY 0.680851 (838 3658);
PAINT GREEN (838 3658);
FORCEPROP 2 LAST CDS_LIB standard
J 0
(900 3650);
PAINT MONO (900 3650);
DISPLAY INVISIBLE (900 3650);
FORCEPROP 1 LAST BODY_TYPE PLUMBING
J 0
(900 3700);
DISPLAY 0.872340 (900 3700);
PAINT GREEN (900 3700);
DISPLAY INVISIBLE (900 3700);
FORCEPROP 1 LAST HDL_TAP TRUE
J 0
(1225 3525);
DISPLAY 0.872340 (1225 3525);
PAINT GREEN (1225 3525);
DISPLAY INVISIBLE (1225 3525);
FORCEPROP 1 LAST PATH I107
J 0
(898 3650);
DISPLAY 0.872340 (898 3650);
PAINT GREEN (898 3650);
DISPLAY INVISIBLE (898 3650);
FORCEADD TAP..1
(900 3500);
FORCEPROP 3 LASTPIN (850 3500) SIG_NAME P5E_CPU0_PE1_RX_DP<11>
J 0
(860 3510);
DISPLAY 0.659574 (860 3510);
PAINT MONO (860 3510);
DISPLAY INVISIBLE (860 3510);
FORCEPROP 1 LASTPIN (850 3500) BN 11
J 0
(838 3508);
DISPLAY 0.680851 (838 3508);
PAINT GREEN (838 3508);
FORCEPROP 2 LAST CDS_LIB standard
J 0
(900 3500);
PAINT MONO (900 3500);
DISPLAY INVISIBLE (900 3500);
FORCEPROP 1 LAST BODY_TYPE PLUMBING
J 0
(900 3550);
DISPLAY 0.872340 (900 3550);
PAINT GREEN (900 3550);
DISPLAY INVISIBLE (900 3550);
FORCEPROP 1 LAST HDL_TAP TRUE
J 0
(1225 3375);
DISPLAY 0.872340 (1225 3375);
PAINT GREEN (1225 3375);
DISPLAY INVISIBLE (1225 3375);
FORCEPROP 1 LAST PATH I108
J 0
(898 3500);
DISPLAY 0.872340 (898 3500);
PAINT GREEN (898 3500);
DISPLAY INVISIBLE (898 3500);
FORCEADD TAP..1
(900 3800);
FORCEPROP 3 LASTPIN (850 3800) SIG_NAME P5E_CPU0_PE1_RX_DP<9>
J 0
(860 3810);
DISPLAY 0.659574 (860 3810);
PAINT MONO (860 3810);
DISPLAY INVISIBLE (860 3810);
FORCEPROP 1 LASTPIN (850 3800) BN 9
J 0
(838 3808);
DISPLAY 0.680851 (838 3808);
PAINT GREEN (838 3808);
FORCEPROP 2 LAST CDS_LIB standard
J 0
(900 3800);
PAINT MONO (900 3800);
DISPLAY INVISIBLE (900 3800);
FORCEPROP 1 LAST BODY_TYPE PLUMBING
J 0
(900 3850);
DISPLAY 0.872340 (900 3850);
PAINT GREEN (900 3850);
DISPLAY INVISIBLE (900 3850);
FORCEPROP 1 LAST HDL_TAP TRUE
J 0
(1225 3675);
DISPLAY 0.872340 (1225 3675);
PAINT GREEN (1225 3675);
DISPLAY INVISIBLE (1225 3675);
FORCEPROP 1 LAST PATH I109
J 0
(898 3800);
DISPLAY 0.872340 (898 3800);
PAINT GREEN (898 3800);
DISPLAY INVISIBLE (898 3800);
FORCEADD Q_CAP..1
(1750 1750);
FORCEPROP 1 LAST PART_NUMBER CH4104K1B00
J 0
(1800 1600);
DISPLAY 0.808511 (1800 1600);
DISPLAY INVISIBLE (1800 1600);
FORCEPROP 1 LAST MATERIAL X7R
J 0
(1800 1650);
DISPLAY 0.638298 (1800 1650);
FORCEPROP 1 LAST PACK_TYPE 0402
J 0
(1800 1600);
DISPLAY 0.638298 (1800 1600);
FORCEPROP 1 LAST VOLTAGE 25V
J 0
(1800 1750);
DISPLAY 0.638298 (1800 1750);
FORCEPROP 1 LAST VALUE 0.1UF
J 0
(1800 1800);
DISPLAY 0.638298 (1800 1800);
FORCEPROP 1 LAST TOLERANCE 10%
J 0
(1800 1700);
DISPLAY 0.638298 (1800 1700);
FORCEPROP 1 LAST $LOCATION C1234
J 0
(1800 1850);
DISPLAY 0.787234 (1800 1850);
FORCEPROP 1 LASTPIN (1750 1850) $PN 1
J 0
(1760 1830);
DISPLAY 0.787234 (1760 1830);
FORCEPROP 1 LASTPIN (1750 1650) $PN 2
J 0
(1760 1630);
DISPLAY 0.787234 (1760 1630);
FORCEPROP 2 LAST CDS_LIB pure_quanta
J 0
(1750 1750);
PAINT MONO (1750 1750);
DISPLAY INVISIBLE (1750 1750);
FORCEPROP 1 LAST PATH I110
J 0
(1800 1900);
DISPLAY 0.978723 (1800 1900);
PAINT WHITE (1800 1900);
DISPLAY INVISIBLE (1800 1900);
FORCEPROP 2 LAST CDS_LOCATION C1234
J 0
(1800 1950);
DISPLAY 1.021277 (1800 1950);
DISPLAY INVISIBLE (1800 1950);
FORCEPROP 2 LAST $SEC 1
J 0
(1800 1950);
DISPLAY 0.680851 (1800 1950);
PAINT MONO (1800 1950);
DISPLAY INVISIBLE (1800 1950);
FORCEPROP 2 LAST CDS_SEC 1
J 0
(1800 1950);
DISPLAY 1.021277 (1800 1950);
DISPLAY INVISIBLE (1800 1950);
FORCEADD Q_CAP..1
(2025 1750);
FORCEPROP 1 LAST PART_NUMBER CH4104K1B00
J 0
(2075 1600);
DISPLAY 0.808511 (2075 1600);
DISPLAY INVISIBLE (2075 1600);
FORCEPROP 1 LAST MATERIAL X7R
J 0
(2075 1650);
DISPLAY 0.638298 (2075 1650);
FORCEPROP 1 LAST PACK_TYPE 0402
J 0
(2075 1600);
DISPLAY 0.638298 (2075 1600);
FORCEPROP 1 LAST TOLERANCE 10%
J 0
(2075 1700);
DISPLAY 0.638298 (2075 1700);
FORCEPROP 1 LAST VOLTAGE 25V
J 0
(2075 1750);
DISPLAY 0.638298 (2075 1750);
FORCEPROP 1 LAST VALUE 0.1UF
J 0
(2075 1800);
DISPLAY 0.638298 (2075 1800);
FORCEPROP 1 LAST $LOCATION C1235
J 0
(2075 1850);
DISPLAY 0.787234 (2075 1850);
FORCEPROP 1 LASTPIN (2025 1850) $PN 1
J 0
(2035 1830);
DISPLAY 0.787234 (2035 1830);
FORCEPROP 1 LASTPIN (2025 1650) $PN 2
J 0
(2035 1630);
DISPLAY 0.787234 (2035 1630);
FORCEPROP 2 LAST CDS_LIB pure_quanta
J 0
(2025 1750);
PAINT MONO (2025 1750);
DISPLAY INVISIBLE (2025 1750);
FORCEPROP 1 LAST PATH I111
J 0
(2075 1900);
DISPLAY 0.978723 (2075 1900);
PAINT WHITE (2075 1900);
DISPLAY INVISIBLE (2075 1900);
FORCEPROP 2 LAST CDS_LOCATION C1235
J 0
(2075 1950);
DISPLAY 1.021277 (2075 1950);
DISPLAY INVISIBLE (2075 1950);
FORCEPROP 2 LAST $SEC 1
J 0
(2075 1950);
DISPLAY 0.680851 (2075 1950);
PAINT MONO (2075 1950);
DISPLAY INVISIBLE (2075 1950);
FORCEPROP 2 LAST CDS_SEC 1
J 0
(2075 1950);
DISPLAY 1.021277 (2075 1950);
DISPLAY INVISIBLE (2075 1950);
FORCEADD UNIVERSAL_GND..1
(2300 1400);
FORCEPROP 3 LASTPIN (2300 1450) SIG_NAME GND\g
J 0
(2310 1460);
DISPLAY 0.659574 (2310 1460);
PAINT MONO (2310 1460);
DISPLAY INVISIBLE (2310 1460);
FORCEPROP 2 LAST CDS_LIB logical_power
J 0
(2300 1400);
PAINT MONO (2300 1400);
DISPLAY INVISIBLE (2300 1400);
FORCEPROP 1 LAST HDL_POWER GND
J 1
(2325 1325);
DISPLAY 0.872340 (2325 1325);
PAINT GREEN (2325 1325);
DISPLAY INVISIBLE (2325 1325);
FORCEPROP 1 LAST PATH I112
J 0
(2375 1400);
DISPLAY 0.872340 (2375 1400);
PAINT AQUA (2375 1400);
DISPLAY INVISIBLE (2375 1400);
FORCEPROP 2 LAST ROOM IO_SLOT
J 1
(2075 1475);
DISPLAY 0.744681 (2075 1475);
DISPLAY INVISIBLE (2075 1475);
FORCEADD Q_CAP..1
(2300 1750);
FORCEPROP 1 LAST PART_NUMBER CH4104K1B00
J 0
(2350 1550);
DISPLAY 0.638298 (2350 1550);
DISPLAY INVISIBLE (2350 1550);
FORCEPROP 1 LAST MATERIAL X7R
J 0
(2350 1650);
DISPLAY 0.638298 (2350 1650);
FORCEPROP 1 LAST VALUE 0.1UF
J 0
(2350 1800);
DISPLAY 0.638298 (2350 1800);
FORCEPROP 1 LAST TOLERANCE 10%
J 0
(2350 1700);
DISPLAY 0.638298 (2350 1700);
FORCEPROP 1 LAST VOLTAGE 25V
J 0
(2350 1750);
DISPLAY 0.638298 (2350 1750);
FORCEPROP 1 LAST PACK_TYPE 0402
J 0
(2350 1600);
DISPLAY 0.638298 (2350 1600);
FORCEPROP 1 LAST $LOCATION C1236
J 0
(2350 1850);
DISPLAY 0.787234 (2350 1850);
FORCEPROP 1 LASTPIN (2300 1850) $PN 1
J 0
(2310 1830);
DISPLAY 0.787234 (2310 1830);
FORCEPROP 1 LASTPIN (2300 1650) $PN 2
J 0
(2310 1630);
DISPLAY 0.787234 (2310 1630);
FORCEPROP 2 LAST CDS_LIB pure_quanta
J 0
(2300 1750);
PAINT MONO (2300 1750);
DISPLAY INVISIBLE (2300 1750);
FORCEPROP 1 LAST PATH I113
J 0
(2350 1900);
DISPLAY 0.978723 (2350 1900);
PAINT WHITE (2350 1900);
DISPLAY INVISIBLE (2350 1900);
FORCEPROP 2 LAST CDS_LOCATION C1236
J 0
(2350 1950);
DISPLAY 1.021277 (2350 1950);
DISPLAY INVISIBLE (2350 1950);
FORCEPROP 2 LAST $SEC 1
J 0
(2350 1950);
DISPLAY 0.680851 (2350 1950);
PAINT MONO (2350 1950);
DISPLAY INVISIBLE (2350 1950);
FORCEPROP 2 LAST CDS_SEC 1
J 0
(2350 1950);
DISPLAY 1.021277 (2350 1950);
DISPLAY INVISIBLE (2350 1950);
FORCEADD Q_CAP..1
(2825 1900);
FORCEPROP 1 LAST PART_NUMBER CH4104K1B00
J 0
(2875 1750);
DISPLAY 0.808511 (2875 1750);
DISPLAY INVISIBLE (2875 1750);
FORCEPROP 1 LAST VALUE 0.1UF
J 0
(2875 1950);
DISPLAY 0.638298 (2875 1950);
FORCEPROP 1 LAST VOLTAGE 25V
J 0
(2875 1900);
DISPLAY 0.638298 (2875 1900);
FORCEPROP 1 LAST TOLERANCE 10%
J 0
(2875 1850);
DISPLAY 0.638298 (2875 1850);
FORCEPROP 1 LAST PACK_TYPE 0402
J 0
(2875 1750);
DISPLAY 0.638298 (2875 1750);
FORCEPROP 1 LAST MATERIAL X7R
J 0
(2875 1800);
DISPLAY 0.638298 (2875 1800);
FORCEPROP 1 LAST $LOCATION C1237
J 0
(2875 2000);
DISPLAY 0.787234 (2875 2000);
FORCEPROP 1 LASTPIN (2825 2000) $PN 1
J 0
(2835 1980);
DISPLAY 0.787234 (2835 1980);
FORCEPROP 1 LASTPIN (2825 1800) $PN 2
J 0
(2835 1780);
DISPLAY 0.787234 (2835 1780);
FORCEPROP 2 LAST CDS_LIB pure_quanta
J 0
(2825 1900);
PAINT MONO (2825 1900);
DISPLAY INVISIBLE (2825 1900);
FORCEPROP 1 LAST PATH I114
J 0
(2875 2050);
DISPLAY 0.978723 (2875 2050);
PAINT WHITE (2875 2050);
DISPLAY INVISIBLE (2875 2050);
FORCEPROP 2 LAST CDS_LOCATION C1237
J 0
(2875 2100);
DISPLAY 1.021277 (2875 2100);
DISPLAY INVISIBLE (2875 2100);
FORCEPROP 2 LAST $SEC 1
J 0
(2875 2100);
DISPLAY 0.680851 (2875 2100);
PAINT MONO (2875 2100);
DISPLAY INVISIBLE (2875 2100);
FORCEPROP 2 LAST CDS_SEC 1
J 0
(2875 2100);
DISPLAY 1.021277 (2875 2100);
DISPLAY INVISIBLE (2875 2100);
FORCEADD Q_CAP..1
(3075 1900);
FORCEPROP 1 LAST PART_NUMBER CH4104K1B00
J 0
(3125 1750);
DISPLAY 0.808511 (3125 1750);
DISPLAY INVISIBLE (3125 1750);
FORCEPROP 1 LAST MATERIAL X7R
J 0
(3125 1800);
DISPLAY 0.638298 (3125 1800);
FORCEPROP 1 LAST TOLERANCE 10%
J 0
(3125 1850);
DISPLAY 0.638298 (3125 1850);
FORCEPROP 1 LAST VOLTAGE 25V
J 0
(3125 1900);
DISPLAY 0.638298 (3125 1900);
FORCEPROP 1 LAST VALUE 0.1UF
J 0
(3125 1950);
DISPLAY 0.638298 (3125 1950);
FORCEPROP 1 LAST PACK_TYPE 0402
J 0
(3125 1750);
DISPLAY 0.638298 (3125 1750);
FORCEPROP 1 LAST $LOCATION C1238
J 0
(3125 2000);
DISPLAY 0.787234 (3125 2000);
FORCEPROP 1 LASTPIN (3075 2000) $PN 1
J 0
(3085 1980);
DISPLAY 0.787234 (3085 1980);
FORCEPROP 1 LASTPIN (3075 1800) $PN 2
J 0
(3085 1780);
DISPLAY 0.787234 (3085 1780);
FORCEPROP 2 LAST CDS_LIB pure_quanta
J 0
(3075 1900);
PAINT MONO (3075 1900);
DISPLAY INVISIBLE (3075 1900);
FORCEPROP 1 LAST PATH I115
J 0
(3125 2050);
DISPLAY 0.978723 (3125 2050);
PAINT WHITE (3125 2050);
DISPLAY INVISIBLE (3125 2050);
FORCEPROP 2 LAST CDS_LOCATION C1238
J 0
(3125 2100);
DISPLAY 1.021277 (3125 2100);
DISPLAY INVISIBLE (3125 2100);
FORCEPROP 2 LAST $SEC 1
J 0
(3125 2100);
DISPLAY 0.680851 (3125 2100);
PAINT MONO (3125 2100);
DISPLAY INVISIBLE (3125 2100);
FORCEPROP 2 LAST CDS_SEC 1
J 0
(3125 2100);
DISPLAY 1.021277 (3125 2100);
DISPLAY INVISIBLE (3125 2100);
FORCEADD Q_CAP..1
(3350 1900);
FORCEPROP 1 LAST PART_NUMBER CH4104K1B00
J 0
(3400 1750);
DISPLAY 0.808511 (3400 1750);
DISPLAY INVISIBLE (3400 1750);
FORCEPROP 1 LAST MATERIAL X7R
J 0
(3400 1800);
DISPLAY 0.638298 (3400 1800);
FORCEPROP 1 LAST PACK_TYPE 0402
J 0
(3400 1750);
DISPLAY 0.638298 (3400 1750);
FORCEPROP 1 LAST TOLERANCE 10%
J 0
(3400 1850);
DISPLAY 0.638298 (3400 1850);
FORCEPROP 1 LAST VOLTAGE 25V
J 0
(3400 1900);
DISPLAY 0.638298 (3400 1900);
FORCEPROP 1 LAST VALUE 0.1UF
J 0
(3400 1950);
DISPLAY 0.638298 (3400 1950);
FORCEPROP 1 LAST $LOCATION C1239
J 0
(3400 2000);
DISPLAY 0.787234 (3400 2000);
FORCEPROP 1 LASTPIN (3350 2000) $PN 1
J 0
(3360 1980);
DISPLAY 0.787234 (3360 1980);
FORCEPROP 1 LASTPIN (3350 1800) $PN 2
J 0
(3360 1780);
DISPLAY 0.787234 (3360 1780);
FORCEPROP 2 LAST CDS_LIB pure_quanta
J 0
(3350 1900);
PAINT MONO (3350 1900);
DISPLAY INVISIBLE (3350 1900);
FORCEPROP 1 LAST PATH I116
J 0
(3400 2050);
DISPLAY 0.978723 (3400 2050);
PAINT WHITE (3400 2050);
DISPLAY INVISIBLE (3400 2050);
FORCEPROP 2 LAST CDS_LOCATION C1239
J 0
(3400 2100);
DISPLAY 1.021277 (3400 2100);
DISPLAY INVISIBLE (3400 2100);
FORCEPROP 2 LAST $SEC 1
J 0
(3400 2100);
DISPLAY 0.680851 (3400 2100);
PAINT MONO (3400 2100);
DISPLAY INVISIBLE (3400 2100);
FORCEPROP 2 LAST CDS_SEC 1
J 0
(3400 2100);
DISPLAY 1.021277 (3400 2100);
DISPLAY INVISIBLE (3400 2100);
FORCEADD OFFPAGE..4
(1150 2650);
FORCEPROP 2 LAST $XR0 155 
J 0
(1336 2650);
DISPLAY 0.638298 (1336 2650);
PAINT MONO (1336 2650);
FORCEPROP 2 LAST CDS_LIB standard
J 0
(1150 2650);
PAINT MONO (1150 2650);
DISPLAY INVISIBLE (1150 2650);
FORCEPROP 1 LAST OFFPAGE TRUE
J 0
(1475 2525);
DISPLAY 0.872340 (1475 2525);
PAINT GREEN (1475 2525);
DISPLAY INVISIBLE (1475 2525);
FORCEPROP 1 LAST COMMENT_BODY TRUE
J 0
(1125 2550);
DISPLAY 0.872340 (1125 2550);
PAINT GREEN (1125 2550);
DISPLAY INVISIBLE (1125 2550);
FORCEPROP 2 LAST PATH I117
J 0
(1350 2700);
DISPLAY 1.021277 (1350 2700);
DISPLAY INVISIBLE (1350 2700);
FORCEADD Q_RES..1
(1500 2750);
FORCEPROP 1 LAST PART_NUMBER CS00002JB13
J 0
(1400 2800);
DISPLAY 0.638298 (1400 2800);
DISPLAY INVISIBLE (1400 2800);
FORCEPROP 1 LAST TOLERANCE 5%
J 0
(1700 2750);
DISPLAY 0.638298 (1700 2750);
FORCEPROP 1 LAST VALUE 0
J 2
(1675 2750);
DISPLAY 0.638298 (1675 2750);
FORCEPROP 1 LAST WATTAGE 1/16W
J 2
(1700 2850);
DISPLAY 0.638298 (1700 2850);
FORCEPROP 1 LAST MATERIAL CHIP
J 0
(1425 2850);
DISPLAY 0.638298 (1425 2850);
FORCEPROP 1 LAST PACK_TYPE 0402LF
J 0
(1775 2750);
DISPLAY 0.638298 (1775 2750);
FORCEPROP 1 LAST $LOCATION R444
J 0
(1225 2750);
DISPLAY 0.638298 (1225 2750);
FORCEPROP 1 LASTPIN (1400 2750) $PN 1
J 0
(1412 2762);
DISPLAY 0.787234 (1412 2762);
FORCEPROP 1 LASTPIN (1600 2750) $PN 2
J 0
(1562 2762);
DISPLAY 0.787234 (1562 2762);
FORCEPROP 2 LAST CDS_LIB pure_quanta
J 0
(1500 2750);
PAINT MONO (1500 2750);
DISPLAY INVISIBLE (1500 2750);
FORCEPROP 1 LAST PATH I118
J 0
(1450 2900);
DISPLAY 0.978723 (1450 2900);
PAINT WHITE (1450 2900);
DISPLAY INVISIBLE (1450 2900);
FORCEPROP 2 LAST CDS_LOCATION R444
J 0
(1450 2950);
DISPLAY 1.021277 (1450 2950);
DISPLAY INVISIBLE (1450 2950);
FORCEPROP 2 LAST $SEC 1
J 0
(1450 2950);
DISPLAY 0.680851 (1450 2950);
PAINT MONO (1450 2950);
DISPLAY INVISIBLE (1450 2950);
FORCEPROP 2 LAST CDS_SEC 1
J 0
(1450 2950);
DISPLAY 1.021277 (1450 2950);
DISPLAY INVISIBLE (1450 2950);
FORCEADD Q_RES..1
(1500 2700);
FORCEPROP 1 LAST PART_NUMBER CS00002JB13
J 0
(1375 2775);
DISPLAY 0.638298 (1375 2775);
DISPLAY INVISIBLE (1375 2775);
FORCEPROP 1 LAST VALUE 0
J 2
(1675 2700);
DISPLAY 0.638298 (1675 2700);
FORCEPROP 1 LAST TOLERANCE 5%
J 0
(1700 2700);
DISPLAY 0.638298 (1700 2700);
FORCEPROP 1 LAST PACK_TYPE 0402LF
J 0
(1775 2700);
DISPLAY 0.638298 (1775 2700);
FORCEPROP 1 LAST $LOCATION R445
J 0
(1225 2700);
DISPLAY 0.638298 (1225 2700);
FORCEPROP 1 LASTPIN (1400 2700) $PN 1
J 0
(1412 2712);
DISPLAY 0.787234 (1412 2712);
FORCEPROP 1 LASTPIN (1600 2700) $PN 2
J 0
(1562 2712);
DISPLAY 0.787234 (1562 2712);
FORCEPROP 1 LAST MATERIAL CHIP
J 0
(1375 2825);
DISPLAY 0.638298 (1375 2825);
DISPLAY INVISIBLE (1375 2825);
FORCEPROP 1 LAST WATTAGE 1/16W
J 2
(1675 2825);
DISPLAY 0.638298 (1675 2825);
DISPLAY INVISIBLE (1675 2825);
FORCEPROP 2 LAST CDS_LIB pure_quanta
J 0
(1500 2700);
PAINT MONO (1500 2700);
DISPLAY INVISIBLE (1500 2700);
FORCEPROP 1 LAST PATH I119
J 0
(1450 2850);
DISPLAY 0.978723 (1450 2850);
PAINT WHITE (1450 2850);
DISPLAY INVISIBLE (1450 2850);
FORCEPROP 2 LAST CDS_LOCATION R445
J 0
(1450 2900);
DISPLAY 1.021277 (1450 2900);
DISPLAY INVISIBLE (1450 2900);
FORCEPROP 2 LAST $SEC 1
J 0
(1450 2900);
DISPLAY 0.680851 (1450 2900);
PAINT MONO (1450 2900);
DISPLAY INVISIBLE (1450 2900);
FORCEPROP 2 LAST CDS_SEC 1
J 0
(1450 2900);
DISPLAY 1.021277 (1450 2900);
DISPLAY INVISIBLE (1450 2900);
FORCEADD OFFPAGE..5
(-2000 1450);
FORCEPROP 2 LAST $XR1 153 
J 0
(-2405 1450);
DISPLAY 0.638298 (-2405 1450);
PAINT MONO (-2405 1450);
FORCEPROP 2 LAST $XR0 213 
J 0
(-2285 1450);
DISPLAY 0.638298 (-2285 1450);
PAINT MONO (-2285 1450);
FORCEPROP 2 LAST CDS_LIB standard
J 0
(-2000 1450);
PAINT MONO (-2000 1450);
DISPLAY INVISIBLE (-2000 1450);
FORCEPROP 1 LAST OFFPAGE TRUE
J 0
(-1675 1325);
DISPLAY 0.872340 (-1675 1325);
PAINT GREEN (-1675 1325);
DISPLAY INVISIBLE (-1675 1325);
FORCEPROP 1 LAST COMMENT_BODY TRUE
J 0
(-1900 1375);
DISPLAY 0.872340 (-1900 1375);
PAINT GREEN (-1900 1375);
DISPLAY INVISIBLE (-1900 1375);
FORCEPROP 2 LAST PATH I12
J 0
(-2300 1500);
DISPLAY 1.021277 (-2300 1500);
DISPLAY INVISIBLE (-2300 1500);
FORCEADD UNIVERSAL_POWER..1
(2825 2250);
FORCEPROP 3 LASTPIN (2825 2200) SIG_NAME P3V3_OCP_SFF\g
J 0
(2835 2210);
DISPLAY 0.659574 (2835 2210);
PAINT MONO (2835 2210);
DISPLAY INVISIBLE (2835 2210);
FORCEPROP 1 LAST HDL_POWER P3V3_OCP_SFF
J 1
(2825 2300);
DISPLAY 0.872340 (2825 2300);
PAINT GREEN (2825 2300);
FORCEPROP 2 LAST CDS_LIB logical_power
J 0
(2825 2250);
PAINT MONO (2825 2250);
DISPLAY INVISIBLE (2825 2250);
FORCEPROP 1 LAST PATH I120
J 0
(2875 2275);
DISPLAY 0.872340 (2875 2275);
PAINT AQUA (2875 2275);
DISPLAY INVISIBLE (2875 2275);
FORCEADD OFFPAGE..4
(2550 2700);
FORCEPROP 2 LAST $XR0 180 
J 0
(2736 2700);
DISPLAY 0.638298 (2736 2700);
PAINT MONO (2736 2700);
FORCEPROP 2 LAST CDS_LIB standard
J 0
(2550 2700);
PAINT MONO (2550 2700);
DISPLAY INVISIBLE (2550 2700);
FORCEPROP 1 LAST OFFPAGE TRUE
J 0
(2875 2575);
DISPLAY 0.872340 (2875 2575);
PAINT GREEN (2875 2575);
DISPLAY INVISIBLE (2875 2575);
FORCEPROP 1 LAST COMMENT_BODY TRUE
J 0
(2525 2600);
DISPLAY 0.872340 (2525 2600);
PAINT GREEN (2525 2600);
DISPLAY INVISIBLE (2525 2600);
FORCEPROP 2 LAST PATH I121
J 0
(2750 2750);
DISPLAY 1.021277 (2750 2750);
DISPLAY INVISIBLE (2750 2750);
FORCEADD OFFPAGE..4
(2550 2750);
FORCEPROP 2 LAST $XR0 180 
J 0
(2736 2750);
DISPLAY 0.638298 (2736 2750);
PAINT MONO (2736 2750);
FORCEPROP 2 LAST CDS_LIB standard
J 0
(2550 2750);
PAINT MONO (2550 2750);
DISPLAY INVISIBLE (2550 2750);
FORCEPROP 1 LAST OFFPAGE TRUE
J 0
(2875 2625);
DISPLAY 0.872340 (2875 2625);
PAINT GREEN (2875 2625);
DISPLAY INVISIBLE (2875 2625);
FORCEPROP 1 LAST COMMENT_BODY TRUE
J 0
(2525 2650);
DISPLAY 0.872340 (2525 2650);
PAINT GREEN (2525 2650);
DISPLAY INVISIBLE (2525 2650);
FORCEPROP 2 LAST PATH I122
J 0
(2750 2800);
DISPLAY 1.021277 (2750 2800);
DISPLAY INVISIBLE (2750 2800);
FORCEADD TAP..1
(750 4250);
FORCEPROP 3 LASTPIN (700 4250) SIG_NAME P5E_CPU0_PE1_RX_DN<7>
J 0
(710 4260);
DISPLAY 0.659574 (710 4260);
PAINT MONO (710 4260);
DISPLAY INVISIBLE (710 4260);
FORCEPROP 1 LASTPIN (700 4250) BN 7
J 0
(688 4258);
DISPLAY 0.680851 (688 4258);
PAINT GREEN (688 4258);
FORCEPROP 2 LAST CDS_LIB standard
J 0
(750 4250);
PAINT MONO (750 4250);
DISPLAY INVISIBLE (750 4250);
FORCEPROP 1 LAST BODY_TYPE PLUMBING
J 0
(750 4300);
DISPLAY 0.872340 (750 4300);
PAINT GREEN (750 4300);
DISPLAY INVISIBLE (750 4300);
FORCEPROP 1 LAST HDL_TAP TRUE
J 0
(1075 4125);
DISPLAY 0.872340 (1075 4125);
PAINT GREEN (1075 4125);
DISPLAY INVISIBLE (1075 4125);
FORCEPROP 1 LAST PATH I123
J 0
(748 4250);
DISPLAY 0.872340 (748 4250);
PAINT GREEN (748 4250);
DISPLAY INVISIBLE (748 4250);
FORCEADD TAP..1
(750 4400);
FORCEPROP 3 LASTPIN (700 4400) SIG_NAME P5E_CPU0_PE1_RX_DN<6>
J 0
(710 4410);
DISPLAY 0.659574 (710 4410);
PAINT MONO (710 4410);
DISPLAY INVISIBLE (710 4410);
FORCEPROP 1 LASTPIN (700 4400) BN 6
J 0
(688 4408);
DISPLAY 0.680851 (688 4408);
PAINT GREEN (688 4408);
FORCEPROP 2 LAST CDS_LIB standard
J 0
(750 4400);
PAINT MONO (750 4400);
DISPLAY INVISIBLE (750 4400);
FORCEPROP 1 LAST BODY_TYPE PLUMBING
J 0
(750 4450);
DISPLAY 0.872340 (750 4450);
PAINT GREEN (750 4450);
DISPLAY INVISIBLE (750 4450);
FORCEPROP 1 LAST HDL_TAP TRUE
J 0
(1075 4275);
DISPLAY 0.872340 (1075 4275);
PAINT GREEN (1075 4275);
DISPLAY INVISIBLE (1075 4275);
FORCEPROP 1 LAST PATH I124
J 0
(748 4400);
DISPLAY 0.872340 (748 4400);
PAINT GREEN (748 4400);
DISPLAY INVISIBLE (748 4400);
FORCEADD TAP..1
(750 4550);
FORCEPROP 3 LASTPIN (700 4550) SIG_NAME P5E_CPU0_PE1_RX_DN<5>
J 0
(710 4560);
DISPLAY 0.659574 (710 4560);
PAINT MONO (710 4560);
DISPLAY INVISIBLE (710 4560);
FORCEPROP 1 LASTPIN (700 4550) BN 5
J 0
(688 4558);
DISPLAY 0.680851 (688 4558);
PAINT GREEN (688 4558);
FORCEPROP 2 LAST CDS_LIB standard
J 0
(750 4550);
PAINT MONO (750 4550);
DISPLAY INVISIBLE (750 4550);
FORCEPROP 1 LAST BODY_TYPE PLUMBING
J 0
(750 4600);
DISPLAY 0.872340 (750 4600);
PAINT GREEN (750 4600);
DISPLAY INVISIBLE (750 4600);
FORCEPROP 1 LAST HDL_TAP TRUE
J 0
(1075 4425);
DISPLAY 0.872340 (1075 4425);
PAINT GREEN (1075 4425);
DISPLAY INVISIBLE (1075 4425);
FORCEPROP 1 LAST PATH I125
J 0
(748 4550);
DISPLAY 0.872340 (748 4550);
PAINT GREEN (748 4550);
DISPLAY INVISIBLE (748 4550);
FORCEADD TAP..1
(750 4700);
FORCEPROP 3 LASTPIN (700 4700) SIG_NAME P5E_CPU0_PE1_RX_DN<4>
J 0
(710 4710);
DISPLAY 0.659574 (710 4710);
PAINT MONO (710 4710);
DISPLAY INVISIBLE (710 4710);
FORCEPROP 1 LASTPIN (700 4700) BN 4
J 0
(688 4708);
DISPLAY 0.680851 (688 4708);
PAINT GREEN (688 4708);
FORCEPROP 2 LAST CDS_LIB standard
J 0
(750 4700);
PAINT MONO (750 4700);
DISPLAY INVISIBLE (750 4700);
FORCEPROP 1 LAST BODY_TYPE PLUMBING
J 0
(750 4750);
DISPLAY 0.872340 (750 4750);
PAINT GREEN (750 4750);
DISPLAY INVISIBLE (750 4750);
FORCEPROP 1 LAST HDL_TAP TRUE
J 0
(1075 4575);
DISPLAY 0.872340 (1075 4575);
PAINT GREEN (1075 4575);
DISPLAY INVISIBLE (1075 4575);
FORCEPROP 1 LAST PATH I126
J 0
(748 4700);
DISPLAY 0.872340 (748 4700);
PAINT GREEN (748 4700);
DISPLAY INVISIBLE (748 4700);
FORCEADD TAP..1
(900 3950);
FORCEPROP 3 LASTPIN (850 3950) SIG_NAME P5E_CPU0_PE1_RX_DP<8>
J 0
(860 3960);
DISPLAY 0.659574 (860 3960);
PAINT MONO (860 3960);
DISPLAY INVISIBLE (860 3960);
FORCEPROP 1 LASTPIN (850 3950) BN 8
J 0
(838 3958);
DISPLAY 0.680851 (838 3958);
PAINT GREEN (838 3958);
FORCEPROP 2 LAST CDS_LIB standard
J 0
(900 3950);
PAINT MONO (900 3950);
DISPLAY INVISIBLE (900 3950);
FORCEPROP 1 LAST BODY_TYPE PLUMBING
J 0
(900 4000);
DISPLAY 0.872340 (900 4000);
PAINT GREEN (900 4000);
DISPLAY INVISIBLE (900 4000);
FORCEPROP 1 LAST HDL_TAP TRUE
J 0
(1225 3825);
DISPLAY 0.872340 (1225 3825);
PAINT GREEN (1225 3825);
DISPLAY INVISIBLE (1225 3825);
FORCEPROP 1 LAST PATH I127
J 0
(898 3950);
DISPLAY 0.872340 (898 3950);
PAINT GREEN (898 3950);
DISPLAY INVISIBLE (898 3950);
FORCEADD TAP..1
(900 4450);
FORCEPROP 3 LASTPIN (850 4450) SIG_NAME P5E_CPU0_PE1_RX_DP<6>
J 0
(860 4460);
DISPLAY 0.659574 (860 4460);
PAINT MONO (860 4460);
DISPLAY INVISIBLE (860 4460);
FORCEPROP 1 LASTPIN (850 4450) BN 6
J 0
(838 4458);
DISPLAY 0.680851 (838 4458);
PAINT GREEN (838 4458);
FORCEPROP 2 LAST CDS_LIB standard
J 0
(900 4450);
PAINT MONO (900 4450);
DISPLAY INVISIBLE (900 4450);
FORCEPROP 1 LAST BODY_TYPE PLUMBING
J 0
(900 4500);
DISPLAY 0.872340 (900 4500);
PAINT GREEN (900 4500);
DISPLAY INVISIBLE (900 4500);
FORCEPROP 1 LAST HDL_TAP TRUE
J 0
(1225 4325);
DISPLAY 0.872340 (1225 4325);
PAINT GREEN (1225 4325);
DISPLAY INVISIBLE (1225 4325);
FORCEPROP 1 LAST PATH I128
J 0
(898 4450);
DISPLAY 0.872340 (898 4450);
PAINT GREEN (898 4450);
DISPLAY INVISIBLE (898 4450);
FORCEADD TAP..1
(900 4300);
FORCEPROP 3 LASTPIN (850 4300) SIG_NAME P5E_CPU0_PE1_RX_DP<7>
J 0
(860 4310);
DISPLAY 0.659574 (860 4310);
PAINT MONO (860 4310);
DISPLAY INVISIBLE (860 4310);
FORCEPROP 1 LASTPIN (850 4300) BN 7
J 0
(838 4308);
DISPLAY 0.680851 (838 4308);
PAINT GREEN (838 4308);
FORCEPROP 2 LAST CDS_LIB standard
J 0
(900 4300);
PAINT MONO (900 4300);
DISPLAY INVISIBLE (900 4300);
FORCEPROP 1 LAST BODY_TYPE PLUMBING
J 0
(900 4350);
DISPLAY 0.872340 (900 4350);
PAINT GREEN (900 4350);
DISPLAY INVISIBLE (900 4350);
FORCEPROP 1 LAST HDL_TAP TRUE
J 0
(1225 4175);
DISPLAY 0.872340 (1225 4175);
PAINT GREEN (1225 4175);
DISPLAY INVISIBLE (1225 4175);
FORCEPROP 1 LAST PATH I129
J 0
(898 4300);
DISPLAY 0.872340 (898 4300);
PAINT GREEN (898 4300);
DISPLAY INVISIBLE (898 4300);
FORCEADD TAP..1
(900 4600);
FORCEPROP 3 LASTPIN (850 4600) SIG_NAME P5E_CPU0_PE1_RX_DP<5>
J 0
(860 4610);
DISPLAY 0.659574 (860 4610);
PAINT MONO (860 4610);
DISPLAY INVISIBLE (860 4610);
FORCEPROP 1 LASTPIN (850 4600) BN 5
J 0
(838 4608);
DISPLAY 0.680851 (838 4608);
PAINT GREEN (838 4608);
FORCEPROP 2 LAST CDS_LIB standard
J 0
(900 4600);
PAINT MONO (900 4600);
DISPLAY INVISIBLE (900 4600);
FORCEPROP 1 LAST BODY_TYPE PLUMBING
J 0
(900 4650);
DISPLAY 0.872340 (900 4650);
PAINT GREEN (900 4650);
DISPLAY INVISIBLE (900 4650);
FORCEPROP 1 LAST HDL_TAP TRUE
J 0
(1225 4475);
DISPLAY 0.872340 (1225 4475);
PAINT GREEN (1225 4475);
DISPLAY INVISIBLE (1225 4475);
FORCEPROP 1 LAST PATH I130
J 0
(898 4600);
DISPLAY 0.872340 (898 4600);
PAINT GREEN (898 4600);
DISPLAY INVISIBLE (898 4600);
FORCEADD TAP..1
(900 4750);
FORCEPROP 3 LASTPIN (850 4750) SIG_NAME P5E_CPU0_PE1_RX_DP<4>
J 0
(860 4760);
DISPLAY 0.659574 (860 4760);
PAINT MONO (860 4760);
DISPLAY INVISIBLE (860 4760);
FORCEPROP 1 LASTPIN (850 4750) BN 4
J 0
(838 4758);
DISPLAY 0.680851 (838 4758);
PAINT GREEN (838 4758);
FORCEPROP 2 LAST CDS_LIB standard
J 0
(900 4750);
PAINT MONO (900 4750);
DISPLAY INVISIBLE (900 4750);
FORCEPROP 1 LAST BODY_TYPE PLUMBING
J 0
(900 4800);
DISPLAY 0.872340 (900 4800);
PAINT GREEN (900 4800);
DISPLAY INVISIBLE (900 4800);
FORCEPROP 1 LAST HDL_TAP TRUE
J 0
(1225 4625);
DISPLAY 0.872340 (1225 4625);
PAINT GREEN (1225 4625);
DISPLAY INVISIBLE (1225 4625);
FORCEPROP 1 LAST PATH I131
J 0
(898 4750);
DISPLAY 0.872340 (898 4750);
PAINT GREEN (898 4750);
DISPLAY INVISIBLE (898 4750);
FORCEADD TAP..1
(750 5000);
FORCEPROP 3 LASTPIN (700 5000) SIG_NAME P5E_CPU0_PE1_RX_DN<3>
J 0
(710 5010);
DISPLAY 0.659574 (710 5010);
PAINT MONO (710 5010);
DISPLAY INVISIBLE (710 5010);
FORCEPROP 1 LASTPIN (700 5000) BN 3
J 0
(688 5008);
DISPLAY 0.680851 (688 5008);
PAINT GREEN (688 5008);
FORCEPROP 2 LAST CDS_LIB standard
J 0
(750 5000);
PAINT MONO (750 5000);
DISPLAY INVISIBLE (750 5000);
FORCEPROP 1 LAST BODY_TYPE PLUMBING
J 0
(750 5050);
DISPLAY 0.872340 (750 5050);
PAINT GREEN (750 5050);
DISPLAY INVISIBLE (750 5050);
FORCEPROP 1 LAST HDL_TAP TRUE
J 0
(1075 4875);
DISPLAY 0.872340 (1075 4875);
PAINT GREEN (1075 4875);
DISPLAY INVISIBLE (1075 4875);
FORCEPROP 1 LAST PATH I132
J 0
(748 5000);
DISPLAY 0.872340 (748 5000);
PAINT GREEN (748 5000);
DISPLAY INVISIBLE (748 5000);
FORCEADD TAP..1
(750 5150);
FORCEPROP 3 LASTPIN (700 5150) SIG_NAME P5E_CPU0_PE1_RX_DN<2>
J 0
(710 5160);
DISPLAY 0.659574 (710 5160);
PAINT MONO (710 5160);
DISPLAY INVISIBLE (710 5160);
FORCEPROP 1 LASTPIN (700 5150) BN 2
J 0
(688 5158);
DISPLAY 0.680851 (688 5158);
PAINT GREEN (688 5158);
FORCEPROP 2 LAST CDS_LIB standard
J 0
(750 5150);
PAINT MONO (750 5150);
DISPLAY INVISIBLE (750 5150);
FORCEPROP 1 LAST BODY_TYPE PLUMBING
J 0
(750 5200);
DISPLAY 0.872340 (750 5200);
PAINT GREEN (750 5200);
DISPLAY INVISIBLE (750 5200);
FORCEPROP 1 LAST HDL_TAP TRUE
J 0
(1075 5025);
DISPLAY 0.872340 (1075 5025);
PAINT GREEN (1075 5025);
DISPLAY INVISIBLE (1075 5025);
FORCEPROP 1 LAST PATH I133
J 0
(748 5150);
DISPLAY 0.872340 (748 5150);
PAINT GREEN (748 5150);
DISPLAY INVISIBLE (748 5150);
FORCEADD TAP..1
(750 5300);
FORCEPROP 3 LASTPIN (700 5300) SIG_NAME P5E_CPU0_PE1_RX_DN<1>
J 0
(710 5310);
DISPLAY 0.659574 (710 5310);
PAINT MONO (710 5310);
DISPLAY INVISIBLE (710 5310);
FORCEPROP 1 LASTPIN (700 5300) BN 1
J 0
(688 5308);
DISPLAY 0.680851 (688 5308);
PAINT GREEN (688 5308);
FORCEPROP 2 LAST CDS_LIB standard
J 0
(750 5300);
PAINT MONO (750 5300);
DISPLAY INVISIBLE (750 5300);
FORCEPROP 1 LAST BODY_TYPE PLUMBING
J 0
(750 5350);
DISPLAY 0.872340 (750 5350);
PAINT GREEN (750 5350);
DISPLAY INVISIBLE (750 5350);
FORCEPROP 1 LAST HDL_TAP TRUE
J 0
(1075 5175);
DISPLAY 0.872340 (1075 5175);
PAINT GREEN (1075 5175);
DISPLAY INVISIBLE (1075 5175);
FORCEPROP 1 LAST PATH I134
J 0
(748 5300);
DISPLAY 0.872340 (748 5300);
PAINT GREEN (748 5300);
DISPLAY INVISIBLE (748 5300);
FORCEADD TAP..1
(900 5200);
FORCEPROP 3 LASTPIN (850 5200) SIG_NAME P5E_CPU0_PE1_RX_DP<2>
J 0
(860 5210);
DISPLAY 0.659574 (860 5210);
PAINT MONO (860 5210);
DISPLAY INVISIBLE (860 5210);
FORCEPROP 1 LASTPIN (850 5200) BN 2
J 0
(838 5208);
DISPLAY 0.680851 (838 5208);
PAINT GREEN (838 5208);
FORCEPROP 2 LAST CDS_LIB standard
J 0
(900 5200);
PAINT MONO (900 5200);
DISPLAY INVISIBLE (900 5200);
FORCEPROP 1 LAST BODY_TYPE PLUMBING
J 0
(900 5250);
DISPLAY 0.872340 (900 5250);
PAINT GREEN (900 5250);
DISPLAY INVISIBLE (900 5250);
FORCEPROP 1 LAST HDL_TAP TRUE
J 0
(1225 5075);
DISPLAY 0.872340 (1225 5075);
PAINT GREEN (1225 5075);
DISPLAY INVISIBLE (1225 5075);
FORCEPROP 1 LAST PATH I136
J 0
(898 5200);
DISPLAY 0.872340 (898 5200);
PAINT GREEN (898 5200);
DISPLAY INVISIBLE (898 5200);
FORCEADD TAP..1
(900 5050);
FORCEPROP 3 LASTPIN (850 5050) SIG_NAME P5E_CPU0_PE1_RX_DP<3>
J 0
(860 5060);
DISPLAY 0.659574 (860 5060);
PAINT MONO (860 5060);
DISPLAY INVISIBLE (860 5060);
FORCEPROP 1 LASTPIN (850 5050) BN 3
J 0
(838 5058);
DISPLAY 0.680851 (838 5058);
PAINT GREEN (838 5058);
FORCEPROP 2 LAST CDS_LIB standard
J 0
(900 5050);
PAINT MONO (900 5050);
DISPLAY INVISIBLE (900 5050);
FORCEPROP 1 LAST BODY_TYPE PLUMBING
J 0
(900 5100);
DISPLAY 0.872340 (900 5100);
PAINT GREEN (900 5100);
DISPLAY INVISIBLE (900 5100);
FORCEPROP 1 LAST HDL_TAP TRUE
J 0
(1225 4925);
DISPLAY 0.872340 (1225 4925);
PAINT GREEN (1225 4925);
DISPLAY INVISIBLE (1225 4925);
FORCEPROP 1 LAST PATH I137
J 0
(898 5050);
DISPLAY 0.872340 (898 5050);
PAINT GREEN (898 5050);
DISPLAY INVISIBLE (898 5050);
FORCEADD TAP..1
(900 5350);
FORCEPROP 3 LASTPIN (850 5350) SIG_NAME P5E_CPU0_PE1_RX_DP<1>
J 0
(860 5360);
DISPLAY 0.659574 (860 5360);
PAINT MONO (860 5360);
DISPLAY INVISIBLE (860 5360);
FORCEPROP 1 LASTPIN (850 5350) BN 1
J 0
(838 5358);
DISPLAY 0.680851 (838 5358);
PAINT GREEN (838 5358);
FORCEPROP 2 LAST CDS_LIB standard
J 0
(900 5350);
PAINT MONO (900 5350);
DISPLAY INVISIBLE (900 5350);
FORCEPROP 1 LAST BODY_TYPE PLUMBING
J 0
(900 5400);
DISPLAY 0.872340 (900 5400);
PAINT GREEN (900 5400);
DISPLAY INVISIBLE (900 5400);
FORCEPROP 1 LAST HDL_TAP TRUE
J 0
(1225 5225);
DISPLAY 0.872340 (1225 5225);
PAINT GREEN (1225 5225);
DISPLAY INVISIBLE (1225 5225);
FORCEPROP 1 LAST PATH I138
J 0
(898 5350);
DISPLAY 0.872340 (898 5350);
PAINT GREEN (898 5350);
DISPLAY INVISIBLE (898 5350);
FORCEADD OFFPAGE..2
(1950 4150);
FORCEPROP 2 LAST $XR1 165 
J 0
(2259 4150);
DISPLAY 0.638298 (2259 4150);
PAINT MONO (2259 4150);
FORCEPROP 2 LAST $XR0 156 
J 0
(2139 4150);
DISPLAY 0.638298 (2139 4150);
PAINT MONO (2139 4150);
FORCEPROP 2 LAST CDS_LIB standard
J 0
(1950 4150);
PAINT MONO (1950 4150);
DISPLAY INVISIBLE (1950 4150);
FORCEPROP 1 LAST OFFPAGE TRUE
J 0
(2275 4025);
DISPLAY 0.872340 (2275 4025);
PAINT GREEN (2275 4025);
DISPLAY INVISIBLE (2275 4025);
FORCEPROP 1 LAST COMMENT_BODY TRUE
J 0
(1905 4055);
DISPLAY 0.872340 (1905 4055);
PAINT GREEN (1905 4055);
DISPLAY INVISIBLE (1905 4055);
FORCEPROP 2 LAST PATH I140
J 0
(2150 4200);
DISPLAY 1.021277 (2150 4200);
DISPLAY INVISIBLE (2150 4200);
FORCEADD OFFPAGE..2
(1950 5525);
FORCEPROP 2 LAST $XR0 29 
J 0
(2139 5525);
DISPLAY 0.638298 (2139 5525);
PAINT MONO (2139 5525);
FORCEPROP 2 LAST CDS_LIB standard
J 0
(1950 5525);
DISPLAY INVISIBLE (1950 5525);
FORCEPROP 1 LAST OFFPAGE TRUE
J 0
(2275 5400);
DISPLAY 0.872340 (2275 5400);
PAINT GREEN (2275 5400);
DISPLAY INVISIBLE (2275 5400);
FORCEPROP 1 LAST COMMENT_BODY TRUE
J 0
(1905 5430);
DISPLAY 0.872340 (1905 5430);
PAINT GREEN (1905 5430);
DISPLAY INVISIBLE (1905 5430);
FORCEPROP 2 LAST PATH I142
J 0
(2150 5575);
DISPLAY 1.021277 (2150 5575);
DISPLAY INVISIBLE (2150 5575);
FORCEADD OFFPAGE..2
(1950 5475);
FORCEPROP 2 LAST $XR0 29 
J 0
(2139 5475);
DISPLAY 0.638298 (2139 5475);
PAINT MONO (2139 5475);
FORCEPROP 2 LAST CDS_LIB standard
J 0
(1950 5475);
DISPLAY INVISIBLE (1950 5475);
FORCEPROP 1 LAST OFFPAGE TRUE
J 0
(2275 5350);
DISPLAY 0.872340 (2275 5350);
PAINT GREEN (2275 5350);
DISPLAY INVISIBLE (2275 5350);
FORCEPROP 1 LAST COMMENT_BODY TRUE
J 0
(1905 5380);
DISPLAY 0.872340 (1905 5380);
PAINT GREEN (1905 5380);
DISPLAY INVISIBLE (1905 5380);
FORCEPROP 2 LAST PATH I143
J 0
(2150 5525);
DISPLAY 1.021277 (2150 5525);
DISPLAY INVISIBLE (2150 5525);
FORCEADD OFFPAGE..4
(1950 5600);
FORCEPROP 2 LAST $XR0 209 
J 0
(2136 5600);
DISPLAY 0.638298 (2136 5600);
PAINT MONO (2136 5600);
FORCEPROP 2 LAST CDS_LIB standard
J 0
(1950 5600);
PAINT MONO (1950 5600);
DISPLAY INVISIBLE (1950 5600);
FORCEPROP 1 LAST OFFPAGE TRUE
J 0
(2275 5475);
DISPLAY 0.872340 (2275 5475);
PAINT GREEN (2275 5475);
DISPLAY INVISIBLE (2275 5475);
FORCEPROP 1 LAST COMMENT_BODY TRUE
J 0
(1925 5500);
DISPLAY 0.872340 (1925 5500);
PAINT GREEN (1925 5500);
DISPLAY INVISIBLE (1925 5500);
FORCEPROP 2 LAST PATH I144
J 0
(2150 5650);
DISPLAY 1.021277 (2150 5650);
DISPLAY INVISIBLE (2150 5650);
FORCEADD OFFPAGE..4
(1950 5650);
FORCEPROP 2 LAST $XR0 209 
J 0
(2136 5650);
DISPLAY 0.638298 (2136 5650);
PAINT MONO (2136 5650);
FORCEPROP 2 LAST CDS_LIB standard
J 0
(1950 5650);
PAINT MONO (1950 5650);
DISPLAY INVISIBLE (1950 5650);
FORCEPROP 1 LAST OFFPAGE TRUE
J 0
(2275 5525);
DISPLAY 0.872340 (2275 5525);
PAINT GREEN (2275 5525);
DISPLAY INVISIBLE (2275 5525);
FORCEPROP 1 LAST COMMENT_BODY TRUE
J 0
(1925 5550);
DISPLAY 0.872340 (1925 5550);
PAINT GREEN (1925 5550);
DISPLAY INVISIBLE (1925 5550);
FORCEPROP 2 LAST PATH I145
J 0
(2150 5700);
DISPLAY 1.021277 (2150 5700);
DISPLAY INVISIBLE (2150 5700);
FORCEADD OFFPAGE..4
(1950 5750);
FORCEPROP 2 LAST $XR1 165 
J 0
(2256 5750);
DISPLAY 0.638298 (2256 5750);
PAINT MONO (2256 5750);
FORCEPROP 2 LAST $XR0 156 
J 0
(2136 5750);
DISPLAY 0.638298 (2136 5750);
PAINT MONO (2136 5750);
FORCEPROP 2 LAST CDS_LIB standard
J 0
(1950 5750);
PAINT MONO (1950 5750);
DISPLAY INVISIBLE (1950 5750);
FORCEPROP 1 LAST OFFPAGE TRUE
J 0
(2275 5625);
DISPLAY 0.872340 (2275 5625);
PAINT GREEN (2275 5625);
DISPLAY INVISIBLE (2275 5625);
FORCEPROP 1 LAST COMMENT_BODY TRUE
J 0
(1925 5650);
DISPLAY 0.872340 (1925 5650);
PAINT GREEN (1925 5650);
DISPLAY INVISIBLE (1925 5650);
FORCEPROP 2 LAST PATH I146
J 0
(2150 5800);
DISPLAY 1.021277 (2150 5800);
DISPLAY INVISIBLE (2150 5800);
FORCEADD OFFPAGE..4
(1950 5800);
FORCEPROP 2 LAST $XR0 155 
J 0
(2136 5800);
DISPLAY 0.638298 (2136 5800);
PAINT MONO (2136 5800);
FORCEPROP 2 LAST CDS_LIB standard
J 0
(1950 5800);
PAINT MONO (1950 5800);
DISPLAY INVISIBLE (1950 5800);
FORCEPROP 1 LAST OFFPAGE TRUE
J 0
(2275 5675);
DISPLAY 0.872340 (2275 5675);
PAINT GREEN (2275 5675);
DISPLAY INVISIBLE (2275 5675);
FORCEPROP 1 LAST COMMENT_BODY TRUE
J 0
(1925 5700);
DISPLAY 0.872340 (1925 5700);
PAINT GREEN (1925 5700);
DISPLAY INVISIBLE (1925 5700);
FORCEPROP 2 LAST PATH I147
J 0
(2150 5850);
DISPLAY 1.021277 (2150 5850);
DISPLAY INVISIBLE (2150 5850);
FORCEADD UNIVERSAL_GND..1
(3100 5325);
FORCEPROP 3 LASTPIN (3100 5375) SIG_NAME GND\g
J 0
(3110 5385);
DISPLAY 0.659574 (3110 5385);
PAINT MONO (3110 5385);
DISPLAY INVISIBLE (3110 5385);
FORCEPROP 2 LAST CDS_LIB logical_power
J 0
(3100 5325);
DISPLAY INVISIBLE (3100 5325);
FORCEPROP 1 LAST HDL_POWER GND
J 1
(3125 5250);
DISPLAY 0.872340 (3125 5250);
PAINT GREEN (3125 5250);
DISPLAY INVISIBLE (3125 5250);
FORCEPROP 1 LAST PATH I148
J 0
(3175 5325);
DISPLAY 0.872340 (3175 5325);
PAINT AQUA (3175 5325);
DISPLAY INVISIBLE (3175 5325);
FORCEPROP 2 LAST ROOM IO_SLOT
J 1
(2875 5400);
DISPLAY 0.744681 (2875 5400);
DISPLAY INVISIBLE (2875 5400);
FORCEADD Q_RES..2
(3100 5600);
FORCEPROP 1 LAST PART_NUMBER CS11002FB07
J 0
(3140 5475);
DISPLAY 0.638298 (3140 5475);
DISPLAY INVISIBLE (3140 5475);
FORCEPROP 1 LAST PACK_TYPE 0402LF
J 0
(3140 5425);
DISPLAY 0.638298 (3140 5425);
FORCEPROP 1 LAST TOLERANCE 1%
J 0
(3145 5625);
DISPLAY 0.638298 (3145 5625);
FORCEPROP 1 LAST WATTAGE 1/16W
J 0
(3140 5575);
DISPLAY 0.638298 (3140 5575);
FORCEPROP 1 LAST MATERIAL CHIP
J 0
(3140 5525);
DISPLAY 0.638298 (3140 5525);
FORCEPROP 1 LAST VALUE 100
J 0
(3145 5675);
DISPLAY 0.638298 (3145 5675);
FORCEPROP 1 LAST $LOCATION R1895
J 0
(3145 5725);
DISPLAY 0.638298 (3145 5725);
FORCEPROP 1 LASTPIN (3100 5700) $PN 1
J 0
(3105 5662);
DISPLAY 0.787234 (3105 5662);
PAINT MONO (3105 5662);
FORCEPROP 1 LASTPIN (3100 5500) $PN 2
J 0
(3105 5510);
DISPLAY 0.787234 (3105 5510);
PAINT MONO (3105 5510);
FORCEPROP 2 LAST CDS_LIB pure_quanta
J 0
(3100 5600);
DISPLAY INVISIBLE (3100 5600);
FORCEPROP 1 LAST PATH I149
J 0
(3150 5775);
DISPLAY 0.978723 (3150 5775);
PAINT WHITE (3150 5775);
DISPLAY INVISIBLE (3150 5775);
FORCEPROP 0 LAST CDS_LOCATION R1895
J 0
(3150 5775);
DISPLAY 1.021277 (3150 5775);
DISPLAY INVISIBLE (3150 5775);
FORCEPROP 0 LAST $SEC 1
J 0
(3150 5775);
DISPLAY 0.680851 (3150 5775);
PAINT MONO (3150 5775);
DISPLAY INVISIBLE (3150 5775);
FORCEPROP 0 LAST CDS_SEC 1
J 0
(3150 5775);
DISPLAY 1.021277 (3150 5775);
DISPLAY INVISIBLE (3150 5775);
FORCEADD OFFPAGE..5
(-2025 1800);
FORCEPROP 2 LAST $XR1 213 
J 0
(-2430 1800);
DISPLAY 0.638298 (-2430 1800);
PAINT MONO (-2430 1800);
FORCEPROP 2 LAST $XR0 153 
J 0
(-2310 1800);
DISPLAY 0.638298 (-2310 1800);
PAINT MONO (-2310 1800);
FORCEPROP 2 LAST CDS_LIB standard
J 0
(-2025 1800);
PAINT MONO (-2025 1800);
DISPLAY INVISIBLE (-2025 1800);
FORCEPROP 1 LAST OFFPAGE TRUE
J 0
(-1700 1675);
DISPLAY 0.872340 (-1700 1675);
PAINT GREEN (-1700 1675);
DISPLAY INVISIBLE (-1700 1675);
FORCEPROP 1 LAST COMMENT_BODY TRUE
J 0
(-1925 1725);
DISPLAY 0.872340 (-1925 1725);
PAINT GREEN (-1925 1725);
DISPLAY INVISIBLE (-1925 1725);
FORCEPROP 2 LAST PATH I15
J 0
(-2325 1850);
DISPLAY 1.021277 (-2325 1850);
DISPLAY INVISIBLE (-2325 1850);
FORCEADD OFFPAGE..3
(3250 5950);
FORCEPROP 2 LAST $XR0 238 
J 0
(3464 5950);
DISPLAY 0.638298 (3464 5950);
PAINT MONO (3464 5950);
FORCEPROP 2 LAST CDS_LIB standard
J 0
(3250 5950);
PAINT MONO (3250 5950);
DISPLAY INVISIBLE (3250 5950);
FORCEPROP 1 LAST OFFPAGE TRUE
J 0
(3575 5825);
DISPLAY 0.872340 (3575 5825);
DISPLAY INVISIBLE (3575 5825);
FORCEPROP 1 LAST COMMENT_BODY TRUE
J 0
(3200 5850);
DISPLAY 0.872340 (3200 5850);
PAINT GREEN (3200 5850);
DISPLAY INVISIBLE (3200 5850);
FORCEPROP 2 LAST PATH I150
J 0
(3625 6000);
DISPLAY 1.021277 (3625 6000);
DISPLAY INVISIBLE (3625 6000);
FORCEADD Q_RES..1
(1750 6000);
FORCEPROP 1 LAST PART_NUMBER CS03322FB03
J 0
(1600 6075);
DISPLAY 0.638298 (1600 6075);
DISPLAY INVISIBLE (1600 6075);
FORCEPROP 1 LAST MATERIAL CHIP
J 0
(1600 6125);
DISPLAY 0.638298 (1600 6125);
FORCEPROP 1 LAST WATTAGE 1/16W
J 2
(1900 6125);
DISPLAY 0.638298 (1900 6125);
FORCEPROP 1 LAST TOLERANCE 1%
J 0
(2000 6000);
DISPLAY 0.638298 (2000 6000);
FORCEPROP 1 LAST PACK_TYPE 0402LF
J 0
(2100 6000);
DISPLAY 0.638298 (2100 6000);
FORCEPROP 1 LAST VALUE 33.2
J 2
(1950 6000);
DISPLAY 0.638298 (1950 6000);
FORCEPROP 1 LAST $LOCATION R424
J 0
(1525 6000);
DISPLAY 0.787234 (1525 6000);
FORCEPROP 1 LASTPIN (1650 6000) $PN 1
J 0
(1662 6012);
DISPLAY 0.787234 (1662 6012);
FORCEPROP 1 LASTPIN (1850 6000) $PN 2
J 0
(1812 6012);
DISPLAY 0.787234 (1812 6012);
FORCEPROP 2 LAST CDS_LIB pure_quanta
J 0
(1750 6000);
PAINT MONO (1750 6000);
DISPLAY INVISIBLE (1750 6000);
FORCEPROP 1 LAST PATH I151
J 0
(1700 6150);
DISPLAY 0.978723 (1700 6150);
PAINT WHITE (1700 6150);
DISPLAY INVISIBLE (1700 6150);
FORCEPROP 2 LAST CDS_LOCATION R424
J 0
(1700 6200);
DISPLAY 1.021277 (1700 6200);
DISPLAY INVISIBLE (1700 6200);
FORCEPROP 2 LAST $SEC 1
J 0
(1700 6200);
DISPLAY 0.680851 (1700 6200);
PAINT MONO (1700 6200);
DISPLAY INVISIBLE (1700 6200);
FORCEPROP 2 LAST CDS_SEC 1
J 0
(1700 6200);
DISPLAY 1.021277 (1700 6200);
DISPLAY INVISIBLE (1700 6200);
FORCEADD OFFPAGE..4
(3250 6000);
FORCEPROP 2 LAST $XR0 238 
J 0
(3436 6000);
DISPLAY 0.638298 (3436 6000);
PAINT MONO (3436 6000);
FORCEPROP 2 LAST CDS_LIB standard
J 0
(3250 6000);
PAINT MONO (3250 6000);
DISPLAY INVISIBLE (3250 6000);
FORCEPROP 1 LAST OFFPAGE TRUE
J 0
(3575 5875);
DISPLAY 0.872340 (3575 5875);
PAINT GREEN (3575 5875);
DISPLAY INVISIBLE (3575 5875);
FORCEPROP 1 LAST COMMENT_BODY TRUE
J 0
(3225 5900);
DISPLAY 0.872340 (3225 5900);
PAINT GREEN (3225 5900);
DISPLAY INVISIBLE (3225 5900);
FORCEPROP 2 LAST PATH I152
J 0
(3600 6050);
DISPLAY 1.021277 (3600 6050);
DISPLAY INVISIBLE (3600 6050);
FORCEADD OFFPAGE..4
(1400 6450);
FORCEPROP 2 LAST $XR0 155 
J 0
(1586 6450);
DISPLAY 0.638298 (1586 6450);
PAINT MONO (1586 6450);
FORCEPROP 2 LAST CDS_LIB standard
J 0
(1400 6450);
PAINT MONO (1400 6450);
DISPLAY INVISIBLE (1400 6450);
FORCEPROP 1 LAST OFFPAGE TRUE
J 0
(1725 6325);
DISPLAY 0.872340 (1725 6325);
PAINT GREEN (1725 6325);
DISPLAY INVISIBLE (1725 6325);
FORCEPROP 1 LAST COMMENT_BODY TRUE
J 0
(1375 6350);
DISPLAY 0.872340 (1375 6350);
PAINT GREEN (1375 6350);
DISPLAY INVISIBLE (1375 6350);
FORCEPROP 2 LAST PATH I153
J 0
(1600 6500);
DISPLAY 1.021277 (1600 6500);
DISPLAY INVISIBLE (1600 6500);
FORCEADD OFFPAGE..4
(1400 6600);
FORCEPROP 2 LAST $XR0 209 
J 0
(1586 6600);
DISPLAY 0.638298 (1586 6600);
PAINT MONO (1586 6600);
FORCEPROP 2 LAST CDS_LIB standard
J 0
(1400 6600);
PAINT MONO (1400 6600);
DISPLAY INVISIBLE (1400 6600);
FORCEPROP 1 LAST OFFPAGE TRUE
J 0
(1725 6475);
DISPLAY 0.872340 (1725 6475);
PAINT GREEN (1725 6475);
DISPLAY INVISIBLE (1725 6475);
FORCEPROP 1 LAST COMMENT_BODY TRUE
J 0
(1375 6500);
DISPLAY 0.872340 (1375 6500);
PAINT GREEN (1375 6500);
DISPLAY INVISIBLE (1375 6500);
FORCEPROP 2 LAST PATH I154
J 0
(1600 6650);
DISPLAY 1.021277 (1600 6650);
DISPLAY INVISIBLE (1600 6650);
FORCEADD OFFPAGE..4
(1400 6550);
FORCEPROP 2 LAST $XR0 209 
J 0
(1586 6550);
DISPLAY 0.638298 (1586 6550);
PAINT MONO (1586 6550);
FORCEPROP 2 LAST CDS_LIB standard
J 0
(1400 6550);
PAINT MONO (1400 6550);
DISPLAY INVISIBLE (1400 6550);
FORCEPROP 1 LAST OFFPAGE TRUE
J 0
(1725 6425);
DISPLAY 0.872340 (1725 6425);
PAINT GREEN (1725 6425);
DISPLAY INVISIBLE (1725 6425);
FORCEPROP 1 LAST COMMENT_BODY TRUE
J 0
(1375 6450);
DISPLAY 0.872340 (1375 6450);
PAINT GREEN (1375 6450);
DISPLAY INVISIBLE (1375 6450);
FORCEPROP 2 LAST PATH I155
J 0
(1600 6600);
DISPLAY 1.021277 (1600 6600);
DISPLAY INVISIBLE (1600 6600);
FORCEADD OFFPAGE..4
(1400 6750);
FORCEPROP 2 LAST $XR0 154 
J 0
(1586 6750);
DISPLAY 0.638298 (1586 6750);
PAINT MONO (1586 6750);
FORCEPROP 2 LAST CDS_LIB standard
J 0
(1400 6750);
PAINT MONO (1400 6750);
DISPLAY INVISIBLE (1400 6750);
FORCEPROP 1 LAST OFFPAGE TRUE
J 0
(1725 6625);
DISPLAY 0.872340 (1725 6625);
PAINT GREEN (1725 6625);
DISPLAY INVISIBLE (1725 6625);
FORCEPROP 1 LAST COMMENT_BODY TRUE
J 0
(1375 6650);
DISPLAY 0.872340 (1375 6650);
PAINT GREEN (1375 6650);
DISPLAY INVISIBLE (1375 6650);
FORCEPROP 2 LAST PATH I156
J 0
(1600 6800);
DISPLAY 1.021277 (1600 6800);
DISPLAY INVISIBLE (1600 6800);
FORCEADD OFFPAGE..4
(1400 6700);
FORCEPROP 2 LAST $XR0 154 
J 0
(1586 6700);
DISPLAY 0.638298 (1586 6700);
PAINT MONO (1586 6700);
FORCEPROP 2 LAST CDS_LIB standard
J 0
(1400 6700);
PAINT MONO (1400 6700);
DISPLAY INVISIBLE (1400 6700);
FORCEPROP 1 LAST OFFPAGE TRUE
J 0
(1725 6575);
DISPLAY 0.872340 (1725 6575);
PAINT GREEN (1725 6575);
DISPLAY INVISIBLE (1725 6575);
FORCEPROP 1 LAST COMMENT_BODY TRUE
J 0
(1375 6600);
DISPLAY 0.872340 (1375 6600);
PAINT GREEN (1375 6600);
DISPLAY INVISIBLE (1375 6600);
FORCEPROP 2 LAST PATH I157
J 0
(1600 6750);
DISPLAY 1.021277 (1600 6750);
DISPLAY INVISIBLE (1600 6750);
FORCEADD OFFPAGE..4
(1400 6800);
FORCEPROP 2 LAST $XR0 154 
J 0
(1586 6800);
DISPLAY 0.638298 (1586 6800);
PAINT MONO (1586 6800);
FORCEPROP 2 LAST CDS_LIB standard
J 0
(1400 6800);
PAINT MONO (1400 6800);
DISPLAY INVISIBLE (1400 6800);
FORCEPROP 1 LAST OFFPAGE TRUE
J 0
(1725 6675);
DISPLAY 0.872340 (1725 6675);
PAINT GREEN (1725 6675);
DISPLAY INVISIBLE (1725 6675);
FORCEPROP 1 LAST COMMENT_BODY TRUE
J 0
(1375 6700);
DISPLAY 0.872340 (1375 6700);
PAINT GREEN (1375 6700);
DISPLAY INVISIBLE (1375 6700);
FORCEPROP 2 LAST PATH I158
J 0
(1600 6850);
DISPLAY 1.021277 (1600 6850);
DISPLAY INVISIBLE (1600 6850);
FORCEADD OFFPAGE..4
(1400 6850);
FORCEPROP 2 LAST $XR0 153 
J 0
(1586 6850);
DISPLAY 0.638298 (1586 6850);
PAINT MONO (1586 6850);
FORCEPROP 2 LAST CDS_LIB standard
J 0
(1400 6850);
PAINT MONO (1400 6850);
DISPLAY INVISIBLE (1400 6850);
FORCEPROP 1 LAST OFFPAGE TRUE
J 0
(1725 6725);
DISPLAY 0.872340 (1725 6725);
PAINT GREEN (1725 6725);
DISPLAY INVISIBLE (1725 6725);
FORCEPROP 1 LAST COMMENT_BODY TRUE
J 0
(1375 6750);
DISPLAY 0.872340 (1375 6750);
PAINT GREEN (1375 6750);
DISPLAY INVISIBLE (1375 6750);
FORCEPROP 2 LAST PATH I159
J 0
(1600 6900);
DISPLAY 1.021277 (1600 6900);
DISPLAY INVISIBLE (1600 6900);
FORCEADD OFFPAGE..5
(-2025 1975);
FORCEPROP 2 LAST $XR1 153 
J 0
(-2430 1975);
DISPLAY 0.638298 (-2430 1975);
PAINT MONO (-2430 1975);
FORCEPROP 2 LAST $XR0 213 
J 0
(-2310 1975);
DISPLAY 0.638298 (-2310 1975);
PAINT MONO (-2310 1975);
FORCEPROP 2 LAST CDS_LIB standard
J 0
(-2025 1975);
PAINT MONO (-2025 1975);
DISPLAY INVISIBLE (-2025 1975);
FORCEPROP 1 LAST OFFPAGE TRUE
J 0
(-1700 1850);
DISPLAY 0.872340 (-1700 1850);
PAINT GREEN (-1700 1850);
DISPLAY INVISIBLE (-1700 1850);
FORCEPROP 1 LAST COMMENT_BODY TRUE
J 0
(-1925 1900);
DISPLAY 0.872340 (-1925 1900);
PAINT GREEN (-1925 1900);
DISPLAY INVISIBLE (-1925 1900);
FORCEPROP 2 LAST PATH I16
J 0
(-2325 2025);
DISPLAY 1.021277 (-2325 2025);
DISPLAY INVISIBLE (-2325 2025);
FORCEADD OFFPAGE..2
(1400 6950);
FORCEPROP 2 LAST $XR0 154 
J 0
(1589 6950);
DISPLAY 0.638298 (1589 6950);
PAINT MONO (1589 6950);
FORCEPROP 2 LAST CDS_LIB standard
J 0
(1400 6950);
DISPLAY INVISIBLE (1400 6950);
FORCEPROP 1 LAST OFFPAGE TRUE
J 0
(1725 6825);
DISPLAY 0.872340 (1725 6825);
PAINT GREEN (1725 6825);
DISPLAY INVISIBLE (1725 6825);
FORCEPROP 1 LAST COMMENT_BODY TRUE
J 0
(1355 6855);
DISPLAY 0.872340 (1355 6855);
PAINT GREEN (1355 6855);
DISPLAY INVISIBLE (1355 6855);
FORCEPROP 2 LAST PATH I160
J 0
(1600 7000);
DISPLAY 1.021277 (1600 7000);
DISPLAY INVISIBLE (1600 7000);
FORCEADD OFFPAGE..4
(1400 6900);
FORCEPROP 2 LAST $XR0 154 
J 0
(1586 6900);
DISPLAY 0.638298 (1586 6900);
PAINT MONO (1586 6900);
FORCEPROP 2 LAST CDS_LIB standard
J 0
(1400 6900);
DISPLAY INVISIBLE (1400 6900);
FORCEPROP 1 LAST OFFPAGE TRUE
J 0
(1725 6775);
DISPLAY 0.872340 (1725 6775);
PAINT GREEN (1725 6775);
DISPLAY INVISIBLE (1725 6775);
FORCEPROP 1 LAST COMMENT_BODY TRUE
J 0
(1375 6800);
DISPLAY 0.872340 (1375 6800);
PAINT GREEN (1375 6800);
DISPLAY INVISIBLE (1375 6800);
FORCEPROP 2 LAST PATH I161
J 0
(1600 6950);
DISPLAY 1.021277 (1600 6950);
DISPLAY INVISIBLE (1600 6950);
FORCEADD OFFPAGE..2
(1400 7000);
FORCEPROP 2 LAST $XR0 155 
J 0
(1589 7000);
DISPLAY 0.638298 (1589 7000);
PAINT MONO (1589 7000);
FORCEPROP 2 LAST CDS_LIB standard
J 0
(1400 7000);
PAINT MONO (1400 7000);
DISPLAY INVISIBLE (1400 7000);
FORCEPROP 1 LAST OFFPAGE TRUE
J 0
(1725 6875);
DISPLAY 0.872340 (1725 6875);
PAINT GREEN (1725 6875);
DISPLAY INVISIBLE (1725 6875);
FORCEPROP 1 LAST COMMENT_BODY TRUE
J 0
(1355 6905);
DISPLAY 0.872340 (1355 6905);
PAINT GREEN (1355 6905);
DISPLAY INVISIBLE (1355 6905);
FORCEPROP 2 LAST PATH I162
J 0
(1600 7050);
DISPLAY 1.021277 (1600 7050);
DISPLAY INVISIBLE (1600 7050);
FORCEADD OFFPAGE..4
(1400 7100);
FORCEPROP 2 LAST $XR0 155 
J 0
(1586 7100);
DISPLAY 0.638298 (1586 7100);
PAINT MONO (1586 7100);
FORCEPROP 2 LAST CDS_LIB standard
J 0
(1400 7100);
PAINT MONO (1400 7100);
DISPLAY INVISIBLE (1400 7100);
FORCEPROP 1 LAST OFFPAGE TRUE
J 0
(1725 6975);
DISPLAY 0.872340 (1725 6975);
PAINT GREEN (1725 6975);
DISPLAY INVISIBLE (1725 6975);
FORCEPROP 1 LAST COMMENT_BODY TRUE
J 0
(1375 7000);
DISPLAY 0.872340 (1375 7000);
PAINT GREEN (1375 7000);
DISPLAY INVISIBLE (1375 7000);
FORCEPROP 2 LAST PATH I163
J 0
(1600 7150);
DISPLAY 1.021277 (1600 7150);
DISPLAY INVISIBLE (1600 7150);
FORCEADD OFFPAGE..4
(1400 7050);
FORCEPROP 2 LAST $XR0 155 
J 0
(1586 7050);
DISPLAY 0.638298 (1586 7050);
PAINT MONO (1586 7050);
FORCEPROP 2 LAST CDS_LIB standard
J 0
(1400 7050);
PAINT MONO (1400 7050);
DISPLAY INVISIBLE (1400 7050);
FORCEPROP 1 LAST OFFPAGE TRUE
J 0
(1725 6925);
DISPLAY 0.872340 (1725 6925);
PAINT GREEN (1725 6925);
DISPLAY INVISIBLE (1725 6925);
FORCEPROP 1 LAST COMMENT_BODY TRUE
J 0
(1375 6950);
DISPLAY 0.872340 (1375 6950);
PAINT GREEN (1375 6950);
DISPLAY INVISIBLE (1375 6950);
FORCEPROP 2 LAST PATH I164
J 0
(1600 7100);
DISPLAY 1.021277 (1600 7100);
DISPLAY INVISIBLE (1600 7100);
FORCEADD UNIVERSAL_GND..1
(3625 1550);
FORCEPROP 3 LASTPIN (3625 1600) SIG_NAME GND\g
J 0
(3635 1610);
DISPLAY 0.659574 (3635 1610);
PAINT MONO (3635 1610);
DISPLAY INVISIBLE (3635 1610);
FORCEPROP 2 LAST CDS_LIB logical_power
J 0
(3625 1550);
PAINT MONO (3625 1550);
DISPLAY INVISIBLE (3625 1550);
FORCEPROP 1 LAST HDL_POWER GND
J 1
(3650 1475);
DISPLAY 0.872340 (3650 1475);
PAINT GREEN (3650 1475);
DISPLAY INVISIBLE (3650 1475);
FORCEPROP 1 LAST PATH I167
J 0
(3700 1550);
DISPLAY 0.872340 (3700 1550);
PAINT AQUA (3700 1550);
DISPLAY INVISIBLE (3700 1550);
FORCEPROP 2 LAST ROOM IO_SLOT
J 1
(3400 1625);
DISPLAY 0.744681 (3400 1625);
DISPLAY INVISIBLE (3400 1625);
FORCEADD Q_CAP..1
(3625 1900);
FORCEPROP 1 LAST PART_NUMBER CH4104K1B00
J 0
(3675 1700);
DISPLAY 0.638298 (3675 1700);
DISPLAY INVISIBLE (3675 1700);
FORCEPROP 1 LAST PACK_TYPE 0402
J 0
(3675 1750);
DISPLAY 0.638298 (3675 1750);
FORCEPROP 1 LAST VALUE 0.1UF
J 0
(3675 1950);
DISPLAY 0.638298 (3675 1950);
FORCEPROP 1 LAST MATERIAL X7R
J 0
(3675 1800);
DISPLAY 0.638298 (3675 1800);
FORCEPROP 1 LAST TOLERANCE 10%
J 0
(3675 1850);
DISPLAY 0.638298 (3675 1850);
FORCEPROP 1 LAST VOLTAGE 25V
J 0
(3675 1900);
DISPLAY 0.638298 (3675 1900);
FORCEPROP 1 LAST $LOCATION C1240
J 0
(3675 2000);
DISPLAY 0.787234 (3675 2000);
FORCEPROP 1 LASTPIN (3625 2000) $PN 1
J 0
(3635 1980);
DISPLAY 0.787234 (3635 1980);
FORCEPROP 1 LASTPIN (3625 1800) $PN 2
J 0
(3635 1780);
DISPLAY 0.787234 (3635 1780);
FORCEPROP 2 LAST CDS_LIB pure_quanta
J 0
(3625 1900);
PAINT MONO (3625 1900);
DISPLAY INVISIBLE (3625 1900);
FORCEPROP 1 LAST PATH I168
J 0
(3675 2050);
DISPLAY 0.978723 (3675 2050);
PAINT WHITE (3675 2050);
DISPLAY INVISIBLE (3675 2050);
FORCEPROP 2 LAST CDS_LOCATION C1240
J 0
(3675 2100);
DISPLAY 1.021277 (3675 2100);
DISPLAY INVISIBLE (3675 2100);
FORCEPROP 2 LAST $SEC 1
J 0
(3675 2100);
DISPLAY 0.680851 (3675 2100);
PAINT MONO (3675 2100);
DISPLAY INVISIBLE (3675 2100);
FORCEPROP 2 LAST CDS_SEC 1
J 0
(3675 2100);
DISPLAY 1.021277 (3675 2100);
DISPLAY INVISIBLE (3675 2100);
FORCEADD TAP..1
R 2
(-1600 3900);
FORCEPROP 3 LASTPIN (-1550 3900) SIG_NAME P5E_CPU0_PE1_TX_C_DN<8>
J 0
(-1540 3910);
DISPLAY 0.659574 (-1540 3910);
PAINT MONO (-1540 3910);
DISPLAY INVISIBLE (-1540 3910);
FORCEPROP 1 LASTPIN (-1550 3900) BN 8
J 2
(-1538 3908);
DISPLAY 0.680851 (-1538 3908);
PAINT GREEN (-1538 3908);
FORCEPROP 2 LAST CDS_LIB standard
J 0
(-1600 3900);
PAINT MONO (-1600 3900);
DISPLAY INVISIBLE (-1600 3900);
FORCEPROP 1 LAST BODY_TYPE PLUMBING
J 2
(-1600 3950);
DISPLAY 0.872340 (-1600 3950);
PAINT GREEN (-1600 3950);
DISPLAY INVISIBLE (-1600 3950);
FORCEPROP 1 LAST HDL_TAP TRUE
J 2
(-1925 3775);
DISPLAY 0.872340 (-1925 3775);
PAINT GREEN (-1925 3775);
DISPLAY INVISIBLE (-1925 3775);
FORCEPROP 1 LAST PATH I169
J 2
(-1598 3900);
DISPLAY 0.872340 (-1598 3900);
PAINT GREEN (-1598 3900);
DISPLAY INVISIBLE (-1598 3900);
FORCEADD TAP..1
R 2
(-1750 3050);
FORCEPROP 3 LASTPIN (-1700 3050) SIG_NAME P5E_CPU0_PE1_TX_C_DP<14>
J 0
(-1690 3060);
DISPLAY 0.659574 (-1690 3060);
PAINT MONO (-1690 3060);
DISPLAY INVISIBLE (-1690 3060);
FORCEPROP 1 LASTPIN (-1700 3050) BN 14
J 2
(-1688 3058);
DISPLAY 0.680851 (-1688 3058);
PAINT GREEN (-1688 3058);
FORCEPROP 2 LAST CDS_LIB standard
J 0
(-1750 3050);
PAINT MONO (-1750 3050);
DISPLAY INVISIBLE (-1750 3050);
FORCEPROP 1 LAST BODY_TYPE PLUMBING
J 2
(-1750 3100);
DISPLAY 0.872340 (-1750 3100);
PAINT GREEN (-1750 3100);
DISPLAY INVISIBLE (-1750 3100);
FORCEPROP 1 LAST HDL_TAP TRUE
J 2
(-2075 2925);
DISPLAY 0.872340 (-2075 2925);
PAINT GREEN (-2075 2925);
DISPLAY INVISIBLE (-2075 2925);
FORCEPROP 1 LAST PATH I17
J 2
(-1748 3050);
DISPLAY 0.872340 (-1748 3050);
PAINT GREEN (-1748 3050);
DISPLAY INVISIBLE (-1748 3050);
FORCEADD OFFPAGE..4
(3250 5900);
FORCEPROP 2 LAST $XR0 154 
J 0
(3466 5900);
DISPLAY 0.638298 (3466 5900);
PAINT MONO (3466 5900);
FORCEPROP 2 LAST CDS_LIB standard
J 0
(3250 5900);
DISPLAY INVISIBLE (3250 5900);
FORCEPROP 1 LAST OFFPAGE TRUE
J 0
(3575 5775);
DISPLAY 0.872340 (3575 5775);
PAINT GREEN (3575 5775);
DISPLAY INVISIBLE (3575 5775);
FORCEPROP 1 LAST COMMENT_BODY TRUE
J 0
(3225 5800);
DISPLAY 0.872340 (3225 5800);
PAINT GREEN (3225 5800);
DISPLAY INVISIBLE (3225 5800);
FORCEPROP 2 LAST PATH I171
J 0
(3425 5975);
DISPLAY 1.021277 (3425 5975);
DISPLAY INVISIBLE (3425 5975);
FORCEADD UNIVERSAL_POWER..1
(-1450 7400);
FORCEPROP 3 LASTPIN (-1450 7350) SIG_NAME P12V_OCP_SFF\g
J 0
(-1440 7360);
DISPLAY 0.659574 (-1440 7360);
PAINT MONO (-1440 7360);
DISPLAY INVISIBLE (-1440 7360);
FORCEPROP 1 LAST HDL_POWER P12V_OCP_SFF
J 1
(-1450 7450);
DISPLAY 0.872340 (-1450 7450);
PAINT GREEN (-1450 7450);
FORCEPROP 2 LAST CDS_LIB logical_power
J 0
(-1450 7400);
DISPLAY INVISIBLE (-1450 7400);
FORCEPROP 1 LAST PATH I173
J 0
(-1400 7425);
DISPLAY 0.872340 (-1400 7425);
PAINT AQUA (-1400 7425);
DISPLAY INVISIBLE (-1400 7425);
FORCEADD UNIVERSAL_POWER..1
(-2275 6175);
FORCEPROP 3 LASTPIN (-2275 6125) SIG_NAME P3V3_OCP_SFF\g
J 0
(-2265 6135);
DISPLAY 0.659574 (-2265 6135);
PAINT MONO (-2265 6135);
DISPLAY INVISIBLE (-2265 6135);
FORCEPROP 1 LAST HDL_POWER P3V3_OCP_SFF
J 1
(-2275 6225);
DISPLAY 0.872340 (-2275 6225);
PAINT GREEN (-2275 6225);
FORCEPROP 2 LAST CDS_LIB logical_power
J 0
(-2275 6175);
DISPLAY INVISIBLE (-2275 6175);
FORCEPROP 1 LAST PATH I174
J 0
(-2225 6200);
DISPLAY 0.872340 (-2225 6200);
PAINT AQUA (-2225 6200);
DISPLAY INVISIBLE (-2225 6200);
FORCEADD TAP..1
R 2
(-1600 5350);
FORCEPROP 3 LASTPIN (-1550 5350) SIG_NAME P5E_CPU0_PE1_TX_C_DN<1>
J 0
(-1540 5360);
DISPLAY 0.659574 (-1540 5360);
PAINT MONO (-1540 5360);
DISPLAY INVISIBLE (-1540 5360);
FORCEPROP 1 LASTPIN (-1550 5350) BN 1
J 2
(-1538 5358);
DISPLAY 0.680851 (-1538 5358);
PAINT GREEN (-1538 5358);
FORCEPROP 2 LAST CDS_LIB standard
J 0
(-1600 5350);
PAINT MONO (-1600 5350);
DISPLAY INVISIBLE (-1600 5350);
FORCEPROP 1 LAST BODY_TYPE PLUMBING
J 2
(-1600 5400);
DISPLAY 0.872340 (-1600 5400);
PAINT GREEN (-1600 5400);
DISPLAY INVISIBLE (-1600 5400);
FORCEPROP 1 LAST HDL_TAP TRUE
J 2
(-1925 5225);
DISPLAY 0.872340 (-1925 5225);
PAINT GREEN (-1925 5225);
DISPLAY INVISIBLE (-1925 5225);
FORCEPROP 1 LAST PATH I176
J 2
(-1598 5350);
DISPLAY 0.872340 (-1598 5350);
PAINT GREEN (-1598 5350);
DISPLAY INVISIBLE (-1598 5350);
FORCEADD TAP..1
R 2
(-1750 5300);
FORCEPROP 3 LASTPIN (-1700 5300) SIG_NAME P5E_CPU0_PE1_TX_C_DP<1>
J 0
(-1690 5310);
DISPLAY 0.659574 (-1690 5310);
PAINT MONO (-1690 5310);
DISPLAY INVISIBLE (-1690 5310);
FORCEPROP 1 LASTPIN (-1700 5300) BN 1
J 2
(-1688 5308);
DISPLAY 0.680851 (-1688 5308);
PAINT GREEN (-1688 5308);
FORCEPROP 2 LAST CDS_LIB standard
J 0
(-1750 5300);
PAINT MONO (-1750 5300);
DISPLAY INVISIBLE (-1750 5300);
FORCEPROP 1 LAST BODY_TYPE PLUMBING
J 2
(-1750 5350);
DISPLAY 0.872340 (-1750 5350);
PAINT GREEN (-1750 5350);
DISPLAY INVISIBLE (-1750 5350);
FORCEPROP 1 LAST HDL_TAP TRUE
J 2
(-2075 5175);
DISPLAY 0.872340 (-2075 5175);
PAINT GREEN (-2075 5175);
DISPLAY INVISIBLE (-2075 5175);
FORCEPROP 1 LAST PATH I177
J 2
(-1748 5300);
DISPLAY 0.872340 (-1748 5300);
PAINT GREEN (-1748 5300);
DISPLAY INVISIBLE (-1748 5300);
FORCEADD TAP..1
R 2
(-1750 5000);
FORCEPROP 3 LASTPIN (-1700 5000) SIG_NAME P5E_CPU0_PE1_TX_C_DP<3>
J 0
(-1690 5010);
DISPLAY 0.659574 (-1690 5010);
PAINT MONO (-1690 5010);
DISPLAY INVISIBLE (-1690 5010);
FORCEPROP 1 LASTPIN (-1700 5000) BN 3
J 2
(-1688 5008);
DISPLAY 0.680851 (-1688 5008);
PAINT GREEN (-1688 5008);
FORCEPROP 2 LAST CDS_LIB standard
J 0
(-1750 5000);
PAINT MONO (-1750 5000);
DISPLAY INVISIBLE (-1750 5000);
FORCEPROP 1 LAST BODY_TYPE PLUMBING
J 2
(-1750 5050);
DISPLAY 0.872340 (-1750 5050);
PAINT GREEN (-1750 5050);
DISPLAY INVISIBLE (-1750 5050);
FORCEPROP 1 LAST HDL_TAP TRUE
J 2
(-2075 4875);
DISPLAY 0.872340 (-2075 4875);
PAINT GREEN (-2075 4875);
DISPLAY INVISIBLE (-2075 4875);
FORCEPROP 1 LAST PATH I179
J 2
(-1748 5000);
DISPLAY 0.872340 (-1748 5000);
PAINT GREEN (-1748 5000);
DISPLAY INVISIBLE (-1748 5000);
FORCEADD TAP..1
R 2
(-1600 5050);
FORCEPROP 3 LASTPIN (-1550 5050) SIG_NAME P5E_CPU0_PE1_TX_C_DN<3>
J 0
(-1540 5060);
DISPLAY 0.659574 (-1540 5060);
PAINT MONO (-1540 5060);
DISPLAY INVISIBLE (-1540 5060);
FORCEPROP 1 LASTPIN (-1550 5050) BN 3
J 2
(-1538 5058);
DISPLAY 0.680851 (-1538 5058);
PAINT GREEN (-1538 5058);
FORCEPROP 2 LAST CDS_LIB standard
J 0
(-1600 5050);
PAINT MONO (-1600 5050);
DISPLAY INVISIBLE (-1600 5050);
FORCEPROP 1 LAST BODY_TYPE PLUMBING
J 2
(-1600 5100);
DISPLAY 0.872340 (-1600 5100);
PAINT GREEN (-1600 5100);
DISPLAY INVISIBLE (-1600 5100);
FORCEPROP 1 LAST HDL_TAP TRUE
J 2
(-1925 4925);
DISPLAY 0.872340 (-1925 4925);
PAINT GREEN (-1925 4925);
DISPLAY INVISIBLE (-1925 4925);
FORCEPROP 1 LAST PATH I180
J 2
(-1598 5050);
DISPLAY 0.872340 (-1598 5050);
PAINT GREEN (-1598 5050);
DISPLAY INVISIBLE (-1598 5050);
FORCEADD TAP..1
R 2
(-1750 4550);
FORCEPROP 3 LASTPIN (-1700 4550) SIG_NAME P5E_CPU0_PE1_TX_C_DP<5>
J 0
(-1690 4560);
DISPLAY 0.659574 (-1690 4560);
PAINT MONO (-1690 4560);
DISPLAY INVISIBLE (-1690 4560);
FORCEPROP 1 LASTPIN (-1700 4550) BN 5
J 2
(-1688 4558);
DISPLAY 0.680851 (-1688 4558);
PAINT GREEN (-1688 4558);
FORCEPROP 2 LAST CDS_LIB standard
J 0
(-1750 4550);
PAINT MONO (-1750 4550);
DISPLAY INVISIBLE (-1750 4550);
FORCEPROP 1 LAST BODY_TYPE PLUMBING
J 2
(-1750 4600);
DISPLAY 0.872340 (-1750 4600);
PAINT GREEN (-1750 4600);
DISPLAY INVISIBLE (-1750 4600);
FORCEPROP 1 LAST HDL_TAP TRUE
J 2
(-2075 4425);
DISPLAY 0.872340 (-2075 4425);
PAINT GREEN (-2075 4425);
DISPLAY INVISIBLE (-2075 4425);
FORCEPROP 1 LAST PATH I182
J 2
(-1748 4550);
DISPLAY 0.872340 (-1748 4550);
PAINT GREEN (-1748 4550);
DISPLAY INVISIBLE (-1748 4550);
FORCEADD TAP..1
R 2
(-1600 4600);
FORCEPROP 3 LASTPIN (-1550 4600) SIG_NAME P5E_CPU0_PE1_TX_C_DN<5>
J 0
(-1540 4610);
DISPLAY 0.659574 (-1540 4610);
PAINT MONO (-1540 4610);
DISPLAY INVISIBLE (-1540 4610);
FORCEPROP 1 LASTPIN (-1550 4600) BN 5
J 2
(-1538 4608);
DISPLAY 0.680851 (-1538 4608);
PAINT GREEN (-1538 4608);
FORCEPROP 2 LAST CDS_LIB standard
J 0
(-1600 4600);
PAINT MONO (-1600 4600);
DISPLAY INVISIBLE (-1600 4600);
FORCEPROP 1 LAST BODY_TYPE PLUMBING
J 2
(-1600 4650);
DISPLAY 0.872340 (-1600 4650);
PAINT GREEN (-1600 4650);
DISPLAY INVISIBLE (-1600 4650);
FORCEPROP 1 LAST HDL_TAP TRUE
J 2
(-1925 4475);
DISPLAY 0.872340 (-1925 4475);
PAINT GREEN (-1925 4475);
DISPLAY INVISIBLE (-1925 4475);
FORCEPROP 1 LAST PATH I183
J 2
(-1598 4600);
DISPLAY 0.872340 (-1598 4600);
PAINT GREEN (-1598 4600);
DISPLAY INVISIBLE (-1598 4600);
FORCEADD TAP..1
R 2
(-1750 4250);
FORCEPROP 3 LASTPIN (-1700 4250) SIG_NAME P5E_CPU0_PE1_TX_C_DP<7>
J 0
(-1690 4260);
DISPLAY 0.659574 (-1690 4260);
PAINT MONO (-1690 4260);
DISPLAY INVISIBLE (-1690 4260);
FORCEPROP 1 LASTPIN (-1700 4250) BN 7
J 2
(-1688 4258);
DISPLAY 0.680851 (-1688 4258);
PAINT GREEN (-1688 4258);
FORCEPROP 2 LAST CDS_LIB standard
J 0
(-1750 4250);
PAINT MONO (-1750 4250);
DISPLAY INVISIBLE (-1750 4250);
FORCEPROP 1 LAST BODY_TYPE PLUMBING
J 2
(-1750 4300);
DISPLAY 0.872340 (-1750 4300);
PAINT GREEN (-1750 4300);
DISPLAY INVISIBLE (-1750 4300);
FORCEPROP 1 LAST HDL_TAP TRUE
J 2
(-2075 4125);
DISPLAY 0.872340 (-2075 4125);
PAINT GREEN (-2075 4125);
DISPLAY INVISIBLE (-2075 4125);
FORCEPROP 1 LAST PATH I185
J 2
(-1748 4250);
DISPLAY 0.872340 (-1748 4250);
PAINT GREEN (-1748 4250);
DISPLAY INVISIBLE (-1748 4250);
FORCEADD TAP..1
R 2
(-1600 4300);
FORCEPROP 3 LASTPIN (-1550 4300) SIG_NAME P5E_CPU0_PE1_TX_C_DN<7>
J 0
(-1540 4310);
DISPLAY 0.659574 (-1540 4310);
PAINT MONO (-1540 4310);
DISPLAY INVISIBLE (-1540 4310);
FORCEPROP 1 LASTPIN (-1550 4300) BN 7
J 2
(-1538 4308);
DISPLAY 0.680851 (-1538 4308);
PAINT GREEN (-1538 4308);
FORCEPROP 2 LAST CDS_LIB standard
J 0
(-1600 4300);
PAINT MONO (-1600 4300);
DISPLAY INVISIBLE (-1600 4300);
FORCEPROP 1 LAST BODY_TYPE PLUMBING
J 2
(-1600 4350);
DISPLAY 0.872340 (-1600 4350);
PAINT GREEN (-1600 4350);
DISPLAY INVISIBLE (-1600 4350);
FORCEPROP 1 LAST HDL_TAP TRUE
J 2
(-1925 4175);
DISPLAY 0.872340 (-1925 4175);
PAINT GREEN (-1925 4175);
DISPLAY INVISIBLE (-1925 4175);
FORCEPROP 1 LAST PATH I186
J 2
(-1598 4300);
DISPLAY 0.872340 (-1598 4300);
PAINT GREEN (-1598 4300);
DISPLAY INVISIBLE (-1598 4300);
FORCEADD TAP..1
R 2
(-1750 3750);
FORCEPROP 3 LASTPIN (-1700 3750) SIG_NAME P5E_CPU0_PE1_TX_C_DP<9>
J 0
(-1690 3760);
DISPLAY 0.659574 (-1690 3760);
PAINT MONO (-1690 3760);
DISPLAY INVISIBLE (-1690 3760);
FORCEPROP 1 LASTPIN (-1700 3750) BN 9
J 2
(-1688 3758);
DISPLAY 0.680851 (-1688 3758);
PAINT GREEN (-1688 3758);
FORCEPROP 2 LAST CDS_LIB standard
J 0
(-1750 3750);
PAINT MONO (-1750 3750);
DISPLAY INVISIBLE (-1750 3750);
FORCEPROP 1 LAST BODY_TYPE PLUMBING
J 2
(-1750 3800);
DISPLAY 0.872340 (-1750 3800);
PAINT GREEN (-1750 3800);
DISPLAY INVISIBLE (-1750 3800);
FORCEPROP 1 LAST HDL_TAP TRUE
J 2
(-2075 3625);
DISPLAY 0.872340 (-2075 3625);
PAINT GREEN (-2075 3625);
DISPLAY INVISIBLE (-2075 3625);
FORCEPROP 1 LAST PATH I188
J 2
(-1748 3750);
DISPLAY 0.872340 (-1748 3750);
PAINT GREEN (-1748 3750);
DISPLAY INVISIBLE (-1748 3750);
FORCEADD TAP..1
R 2
(-1600 3800);
FORCEPROP 3 LASTPIN (-1550 3800) SIG_NAME P5E_CPU0_PE1_TX_C_DN<9>
J 0
(-1540 3810);
DISPLAY 0.659574 (-1540 3810);
PAINT MONO (-1540 3810);
DISPLAY INVISIBLE (-1540 3810);
FORCEPROP 1 LASTPIN (-1550 3800) BN 9
J 2
(-1538 3808);
DISPLAY 0.680851 (-1538 3808);
PAINT GREEN (-1538 3808);
FORCEPROP 2 LAST CDS_LIB standard
J 0
(-1600 3800);
PAINT MONO (-1600 3800);
DISPLAY INVISIBLE (-1600 3800);
FORCEPROP 1 LAST BODY_TYPE PLUMBING
J 2
(-1600 3850);
DISPLAY 0.872340 (-1600 3850);
PAINT GREEN (-1600 3850);
DISPLAY INVISIBLE (-1600 3850);
FORCEPROP 1 LAST HDL_TAP TRUE
J 2
(-1925 3675);
DISPLAY 0.872340 (-1925 3675);
PAINT GREEN (-1925 3675);
DISPLAY INVISIBLE (-1925 3675);
FORCEPROP 1 LAST PATH I189
J 2
(-1598 3800);
DISPLAY 0.872340 (-1598 3800);
PAINT GREEN (-1598 3800);
DISPLAY INVISIBLE (-1598 3800);
FORCEADD TAP..1
R 2
(-1750 3450);
FORCEPROP 3 LASTPIN (-1700 3450) SIG_NAME P5E_CPU0_PE1_TX_C_DP<11>
J 0
(-1690 3460);
DISPLAY 0.659574 (-1690 3460);
PAINT MONO (-1690 3460);
DISPLAY INVISIBLE (-1690 3460);
FORCEPROP 1 LASTPIN (-1700 3450) BN 11
J 2
(-1688 3458);
DISPLAY 0.680851 (-1688 3458);
PAINT GREEN (-1688 3458);
FORCEPROP 2 LAST CDS_LIB standard
J 0
(-1750 3450);
PAINT MONO (-1750 3450);
DISPLAY INVISIBLE (-1750 3450);
FORCEPROP 1 LAST BODY_TYPE PLUMBING
J 2
(-1750 3500);
DISPLAY 0.872340 (-1750 3500);
PAINT GREEN (-1750 3500);
DISPLAY INVISIBLE (-1750 3500);
FORCEPROP 1 LAST HDL_TAP TRUE
J 2
(-2075 3325);
DISPLAY 0.872340 (-2075 3325);
PAINT GREEN (-2075 3325);
DISPLAY INVISIBLE (-2075 3325);
FORCEPROP 1 LAST PATH I191
J 2
(-1748 3450);
DISPLAY 0.872340 (-1748 3450);
PAINT GREEN (-1748 3450);
DISPLAY INVISIBLE (-1748 3450);
FORCEADD TAP..1
R 2
(-1600 3500);
FORCEPROP 3 LASTPIN (-1550 3500) SIG_NAME P5E_CPU0_PE1_TX_C_DN<11>
J 0
(-1540 3510);
DISPLAY 0.659574 (-1540 3510);
PAINT MONO (-1540 3510);
DISPLAY INVISIBLE (-1540 3510);
FORCEPROP 1 LASTPIN (-1550 3500) BN 11
J 2
(-1538 3508);
DISPLAY 0.680851 (-1538 3508);
PAINT GREEN (-1538 3508);
FORCEPROP 2 LAST CDS_LIB standard
J 0
(-1600 3500);
PAINT MONO (-1600 3500);
DISPLAY INVISIBLE (-1600 3500);
FORCEPROP 1 LAST BODY_TYPE PLUMBING
J 2
(-1600 3550);
DISPLAY 0.872340 (-1600 3550);
PAINT GREEN (-1600 3550);
DISPLAY INVISIBLE (-1600 3550);
FORCEPROP 1 LAST HDL_TAP TRUE
J 2
(-1925 3375);
DISPLAY 0.872340 (-1925 3375);
PAINT GREEN (-1925 3375);
DISPLAY INVISIBLE (-1925 3375);
FORCEPROP 1 LAST PATH I192
J 2
(-1598 3500);
DISPLAY 0.872340 (-1598 3500);
PAINT GREEN (-1598 3500);
DISPLAY INVISIBLE (-1598 3500);
FORCEADD TAP..1
R 2
(-1750 3150);
FORCEPROP 3 LASTPIN (-1700 3150) SIG_NAME P5E_CPU0_PE1_TX_C_DP<13>
J 0
(-1690 3160);
DISPLAY 0.659574 (-1690 3160);
PAINT MONO (-1690 3160);
DISPLAY INVISIBLE (-1690 3160);
FORCEPROP 1 LASTPIN (-1700 3150) BN 13
J 2
(-1688 3158);
DISPLAY 0.680851 (-1688 3158);
PAINT GREEN (-1688 3158);
FORCEPROP 2 LAST CDS_LIB standard
J 0
(-1750 3150);
PAINT MONO (-1750 3150);
DISPLAY INVISIBLE (-1750 3150);
FORCEPROP 1 LAST BODY_TYPE PLUMBING
J 2
(-1750 3200);
DISPLAY 0.872340 (-1750 3200);
PAINT GREEN (-1750 3200);
DISPLAY INVISIBLE (-1750 3200);
FORCEPROP 1 LAST HDL_TAP TRUE
J 2
(-2075 3025);
DISPLAY 0.872340 (-2075 3025);
PAINT GREEN (-2075 3025);
DISPLAY INVISIBLE (-2075 3025);
FORCEPROP 1 LAST PATH I194
J 2
(-1748 3150);
DISPLAY 0.872340 (-1748 3150);
PAINT GREEN (-1748 3150);
DISPLAY INVISIBLE (-1748 3150);
FORCEADD TAP..1
R 2
(-1600 3200);
FORCEPROP 3 LASTPIN (-1550 3200) SIG_NAME P5E_CPU0_PE1_TX_C_DN<13>
J 0
(-1540 3210);
DISPLAY 0.659574 (-1540 3210);
PAINT MONO (-1540 3210);
DISPLAY INVISIBLE (-1540 3210);
FORCEPROP 1 LASTPIN (-1550 3200) BN 13
J 2
(-1538 3208);
DISPLAY 0.680851 (-1538 3208);
PAINT GREEN (-1538 3208);
FORCEPROP 2 LAST CDS_LIB standard
J 0
(-1600 3200);
PAINT MONO (-1600 3200);
DISPLAY INVISIBLE (-1600 3200);
FORCEPROP 1 LAST BODY_TYPE PLUMBING
J 2
(-1600 3250);
DISPLAY 0.872340 (-1600 3250);
PAINT GREEN (-1600 3250);
DISPLAY INVISIBLE (-1600 3250);
FORCEPROP 1 LAST HDL_TAP TRUE
J 2
(-1925 3075);
DISPLAY 0.872340 (-1925 3075);
PAINT GREEN (-1925 3075);
DISPLAY INVISIBLE (-1925 3075);
FORCEPROP 1 LAST PATH I195
J 2
(-1598 3200);
DISPLAY 0.872340 (-1598 3200);
PAINT GREEN (-1598 3200);
DISPLAY INVISIBLE (-1598 3200);
FORCEADD TAP..1
R 2
(-1750 2850);
FORCEPROP 3 LASTPIN (-1700 2850) SIG_NAME P5E_CPU0_PE1_TX_C_DP<15>
J 0
(-1690 2860);
DISPLAY 0.659574 (-1690 2860);
PAINT MONO (-1690 2860);
DISPLAY INVISIBLE (-1690 2860);
FORCEPROP 1 LASTPIN (-1700 2850) BN 15
J 2
(-1688 2858);
DISPLAY 0.680851 (-1688 2858);
PAINT GREEN (-1688 2858);
FORCEPROP 2 LAST CDS_LIB standard
J 0
(-1750 2850);
PAINT MONO (-1750 2850);
DISPLAY INVISIBLE (-1750 2850);
FORCEPROP 1 LAST BODY_TYPE PLUMBING
J 2
(-1750 2900);
DISPLAY 0.872340 (-1750 2900);
PAINT GREEN (-1750 2900);
DISPLAY INVISIBLE (-1750 2900);
FORCEPROP 1 LAST HDL_TAP TRUE
J 2
(-2075 2725);
DISPLAY 0.872340 (-2075 2725);
PAINT GREEN (-2075 2725);
DISPLAY INVISIBLE (-2075 2725);
FORCEPROP 1 LAST PATH I197
J 2
(-1748 2850);
DISPLAY 0.872340 (-1748 2850);
PAINT GREEN (-1748 2850);
DISPLAY INVISIBLE (-1748 2850);
FORCEADD TAP..1
R 2
(-1600 2900);
FORCEPROP 3 LASTPIN (-1550 2900) SIG_NAME P5E_CPU0_PE1_TX_C_DN<15>
J 0
(-1540 2910);
DISPLAY 0.659574 (-1540 2910);
PAINT MONO (-1540 2910);
DISPLAY INVISIBLE (-1540 2910);
FORCEPROP 1 LASTPIN (-1550 2900) BN 15
J 2
(-1538 2908);
DISPLAY 0.680851 (-1538 2908);
PAINT GREEN (-1538 2908);
FORCEPROP 2 LAST CDS_LIB standard
J 0
(-1600 2900);
PAINT MONO (-1600 2900);
DISPLAY INVISIBLE (-1600 2900);
FORCEPROP 1 LAST BODY_TYPE PLUMBING
J 2
(-1600 2950);
DISPLAY 0.872340 (-1600 2950);
PAINT GREEN (-1600 2950);
DISPLAY INVISIBLE (-1600 2950);
FORCEPROP 1 LAST HDL_TAP TRUE
J 2
(-1925 2775);
DISPLAY 0.872340 (-1925 2775);
PAINT GREEN (-1925 2775);
DISPLAY INVISIBLE (-1925 2775);
FORCEPROP 1 LAST PATH I198
J 2
(-1598 2900);
DISPLAY 0.872340 (-1598 2900);
PAINT GREEN (-1598 2900);
DISPLAY INVISIBLE (-1598 2900);
FORCEADD SCONN168_ME1016810202011..1
(-375 4725);
FORCEPROP 1 LAST PART_NUMBER DFHSG8FR011
J 0
(-864 7345);
DISPLAY 0.723404 (-864 7345);
PAINT GREEN (-864 7345);
DISPLAY INVISIBLE (-864 7345);
FORCEPROP 2 LAST PART_TYPE SMLF
J 0
(-850 7600);
DISPLAY 1.021277 (-850 7600);
FORCEPROP 1 LAST MATERIAL IO
J 0
(-864 7218);
DISPLAY 0.723404 (-864 7218);
PAINT GREEN (-864 7218);
FORCEPROP 2 LAST VALUE SCONN168_ME1016810202011
J 0
(-850 7550);
DISPLAY 1.021277 (-850 7550);
FORCEPROP 1 LAST LOCATION J37
J 0
(-864 7492);
DISPLAY 0.723404 (-864 7492);
PAINT GREEN (-864 7492);
FORCEPROP 2 LASTPIN (-1025 5800) $PN B11
J 2
(-1035 5810);
DISPLAY 0.680851 (-1035 5810);
PAINT MONO (-1035 5810);
FORCEPROP 2 LASTPIN (-1025 6300) $PN B1
J 2
(-1035 6310);
DISPLAY 0.680851 (-1035 6310);
PAINT MONO (-1035 6310);
FORCEPROP 2 LASTPIN (-1025 6250) $PN B2
J 2
(-1035 6260);
DISPLAY 0.680851 (-1035 6260);
PAINT MONO (-1035 6260);
FORCEPROP 2 LASTPIN (-1025 6200) $PN B3
J 2
(-1035 6210);
DISPLAY 0.680851 (-1035 6210);
PAINT MONO (-1035 6210);
FORCEPROP 2 LASTPIN (-1025 6150) $PN B4
J 2
(-1035 6160);
DISPLAY 0.680851 (-1035 6160);
PAINT MONO (-1035 6160);
FORCEPROP 2 LASTPIN (-1025 6100) $PN B5
J 2
(-1035 6110);
DISPLAY 0.680851 (-1035 6110);
PAINT MONO (-1035 6110);
FORCEPROP 2 LASTPIN (-1025 6050) $PN B6
J 2
(-1035 6060);
DISPLAY 0.680851 (-1035 6060);
PAINT MONO (-1035 6060);
FORCEPROP 2 LASTPIN (-1025 5750) $PN B12
J 2
(-1035 5760);
DISPLAY 0.680851 (-1035 5760);
PAINT MONO (-1035 5760);
FORCEPROP 2 LASTPIN (-1025 6000) $PN B7
J 2
(-1035 6010);
DISPLAY 0.680851 (-1035 6010);
PAINT MONO (-1035 6010);
FORCEPROP 2 LASTPIN (-1025 5950) $PN B8
J 2
(-1035 5960);
DISPLAY 0.680851 (-1035 5960);
PAINT MONO (-1035 5960);
FORCEPROP 2 LASTPIN (-1025 5900) $PN B9
J 2
(-1035 5910);
DISPLAY 0.680851 (-1035 5910);
PAINT MONO (-1035 5910);
FORCEPROP 2 LASTPIN (-1025 6850) $PN OB6
J 2
(-1035 6860);
DISPLAY 0.680851 (-1035 6860);
PAINT MONO (-1035 6860);
FORCEPROP 2 LASTPIN (-1025 6950) $PN OB4
J 2
(-1035 6960);
DISPLAY 0.680851 (-1035 6960);
PAINT MONO (-1035 6960);
FORCEPROP 2 LASTPIN (-1025 6900) $PN OB5
J 2
(-1035 6910);
DISPLAY 0.680851 (-1035 6910);
PAINT MONO (-1035 6910);
FORCEPROP 2 LASTPIN (275 2550) $PN G1
J 0
(285 2560);
DISPLAY 0.680851 (285 2560);
PAINT MONO (285 2560);
FORCEPROP 2 LASTPIN (275 2500) $PN G2
J 0
(285 2510);
DISPLAY 0.680851 (285 2510);
PAINT MONO (285 2510);
FORCEPROP 2 LASTPIN (275 2450) $PN G3
J 0
(285 2460);
DISPLAY 0.680851 (285 2460);
PAINT MONO (285 2460);
FORCEPROP 2 LASTPIN (275 2400) $PN G4
J 0
(285 2410);
DISPLAY 0.680851 (285 2410);
PAINT MONO (285 2410);
FORCEPROP 2 LASTPIN (275 2350) $PN G5
J 0
(285 2360);
DISPLAY 0.680851 (285 2360);
PAINT MONO (285 2360);
FORCEPROP 2 LASTPIN (275 6300) $PN A1
J 0
(285 6310);
DISPLAY 0.680851 (285 6310);
PAINT MONO (285 6310);
FORCEPROP 2 LASTPIN (275 6250) $PN A2
J 0
(285 6260);
DISPLAY 0.680851 (285 6260);
PAINT MONO (285 6260);
FORCEPROP 2 LASTPIN (275 6200) $PN A3
J 0
(285 6210);
DISPLAY 0.680851 (285 6210);
PAINT MONO (285 6210);
FORCEPROP 2 LASTPIN (275 6150) $PN A4
J 0
(285 6160);
DISPLAY 0.680851 (285 6160);
PAINT MONO (285 6160);
FORCEPROP 2 LASTPIN (275 6100) $PN A5
J 0
(285 6110);
DISPLAY 0.680851 (285 6110);
PAINT MONO (285 6110);
FORCEPROP 2 LASTPIN (275 6050) $PN A6
J 0
(285 6060);
DISPLAY 0.680851 (285 6060);
PAINT MONO (285 6060);
FORCEPROP 2 LASTPIN (275 5700) $PN A13
J 0
(285 5710);
DISPLAY 0.680851 (285 5710);
PAINT MONO (285 5710);
FORCEPROP 2 LASTPIN (275 5550) $PN A16
J 0
(285 5560);
DISPLAY 0.680851 (285 5560);
PAINT MONO (285 5560);
FORCEPROP 2 LASTPIN (275 5400) $PN A19
J 0
(285 5410);
DISPLAY 0.680851 (285 5410);
PAINT MONO (285 5410);
FORCEPROP 2 LASTPIN (275 5250) $PN A22
J 0
(285 5260);
DISPLAY 0.680851 (285 5260);
PAINT MONO (285 5260);
FORCEPROP 2 LASTPIN (275 5100) $PN A25
J 0
(285 5110);
DISPLAY 0.680851 (285 5110);
PAINT MONO (285 5110);
FORCEPROP 2 LASTPIN (275 4950) $PN A28
J 0
(285 4960);
DISPLAY 0.680851 (285 4960);
PAINT MONO (285 4960);
FORCEPROP 2 LASTPIN (275 4800) $PN A29
J 0
(285 4810);
DISPLAY 0.680851 (285 4810);
PAINT MONO (285 4810);
FORCEPROP 2 LASTPIN (275 4650) $PN A32
J 0
(285 4660);
DISPLAY 0.680851 (285 4660);
PAINT MONO (285 4660);
FORCEPROP 2 LASTPIN (275 4500) $PN A35
J 0
(285 4510);
DISPLAY 0.680851 (285 4510);
PAINT MONO (285 4510);
FORCEPROP 2 LASTPIN (275 4350) $PN A38
J 0
(285 4360);
DISPLAY 0.680851 (285 4360);
PAINT MONO (285 4360);
FORCEPROP 2 LASTPIN (275 4200) $PN A41
J 0
(285 4210);
DISPLAY 0.680851 (285 4210);
PAINT MONO (285 4210);
FORCEPROP 2 LASTPIN (275 4000) $PN A43
J 0
(285 4010);
DISPLAY 0.680851 (285 4010);
PAINT MONO (285 4010);
FORCEPROP 2 LASTPIN (275 3850) $PN A46
J 0
(285 3860);
DISPLAY 0.680851 (285 3860);
PAINT MONO (285 3860);
FORCEPROP 2 LASTPIN (275 3700) $PN A49
J 0
(285 3710);
DISPLAY 0.680851 (285 3710);
PAINT MONO (285 3710);
FORCEPROP 2 LASTPIN (275 3550) $PN A52
J 0
(285 3560);
DISPLAY 0.680851 (285 3560);
PAINT MONO (285 3560);
FORCEPROP 2 LASTPIN (275 3400) $PN A55
J 0
(285 3410);
DISPLAY 0.680851 (285 3410);
PAINT MONO (285 3410);
FORCEPROP 2 LASTPIN (275 3250) $PN A58
J 0
(285 3260);
DISPLAY 0.680851 (285 3260);
PAINT MONO (285 3260);
FORCEPROP 2 LASTPIN (275 3100) $PN A61
J 0
(285 3110);
DISPLAY 0.680851 (285 3110);
PAINT MONO (285 3110);
FORCEPROP 2 LASTPIN (275 2950) $PN A64
J 0
(285 2960);
DISPLAY 0.680851 (285 2960);
PAINT MONO (285 2960);
FORCEPROP 2 LASTPIN (275 2800) $PN A67
J 0
(285 2810);
DISPLAY 0.680851 (285 2810);
PAINT MONO (285 2810);
FORCEPROP 2 LASTPIN (-1025 5700) $PN B13
J 2
(-1035 5710);
DISPLAY 0.680851 (-1035 5710);
PAINT MONO (-1035 5710);
FORCEPROP 2 LASTPIN (-1025 5550) $PN B16
J 2
(-1035 5560);
DISPLAY 0.680851 (-1035 5560);
PAINT MONO (-1035 5560);
FORCEPROP 2 LASTPIN (-1025 5400) $PN B19
J 2
(-1035 5410);
DISPLAY 0.680851 (-1035 5410);
PAINT MONO (-1035 5410);
FORCEPROP 2 LASTPIN (-1025 5250) $PN B22
J 2
(-1035 5260);
DISPLAY 0.680851 (-1035 5260);
PAINT MONO (-1035 5260);
FORCEPROP 2 LASTPIN (-1025 5100) $PN B25
J 2
(-1035 5110);
DISPLAY 0.680851 (-1035 5110);
PAINT MONO (-1035 5110);
FORCEPROP 2 LASTPIN (-1025 4950) $PN B28
J 2
(-1035 4960);
DISPLAY 0.680851 (-1035 4960);
PAINT MONO (-1035 4960);
FORCEPROP 2 LASTPIN (-1025 4800) $PN B29
J 2
(-1035 4810);
DISPLAY 0.680851 (-1035 4810);
PAINT MONO (-1035 4810);
FORCEPROP 2 LASTPIN (-1025 4650) $PN B32
J 2
(-1035 4660);
DISPLAY 0.680851 (-1035 4660);
PAINT MONO (-1035 4660);
FORCEPROP 2 LASTPIN (-1025 4500) $PN B35
J 2
(-1035 4510);
DISPLAY 0.680851 (-1035 4510);
PAINT MONO (-1035 4510);
FORCEPROP 2 LASTPIN (-1025 4350) $PN B38
J 2
(-1035 4360);
DISPLAY 0.680851 (-1035 4360);
PAINT MONO (-1035 4360);
FORCEPROP 2 LASTPIN (-1025 4200) $PN B41
J 2
(-1035 4210);
DISPLAY 0.680851 (-1035 4210);
PAINT MONO (-1035 4210);
FORCEPROP 2 LASTPIN (-1025 4000) $PN B43
J 2
(-1035 4010);
DISPLAY 0.680851 (-1035 4010);
PAINT MONO (-1035 4010);
FORCEPROP 2 LASTPIN (-1025 3850) $PN B46
J 2
(-1035 3860);
DISPLAY 0.680851 (-1035 3860);
PAINT MONO (-1035 3860);
FORCEPROP 2 LASTPIN (-1025 3700) $PN B49
J 2
(-1035 3710);
DISPLAY 0.680851 (-1035 3710);
PAINT MONO (-1035 3710);
FORCEPROP 2 LASTPIN (-1025 3550) $PN B52
J 2
(-1035 3560);
DISPLAY 0.680851 (-1035 3560);
PAINT MONO (-1035 3560);
FORCEPROP 2 LASTPIN (-1025 3400) $PN B55
J 2
(-1035 3410);
DISPLAY 0.680851 (-1035 3410);
PAINT MONO (-1035 3410);
FORCEPROP 2 LASTPIN (-1025 3250) $PN B58
J 2
(-1035 3260);
DISPLAY 0.680851 (-1035 3260);
PAINT MONO (-1035 3260);
FORCEPROP 2 LASTPIN (-1025 3100) $PN B61
J 2
(-1035 3110);
DISPLAY 0.680851 (-1035 3110);
PAINT MONO (-1035 3110);
FORCEPROP 2 LASTPIN (-1025 2950) $PN B64
J 2
(-1035 2960);
DISPLAY 0.680851 (-1035 2960);
PAINT MONO (-1035 2960);
FORCEPROP 2 LASTPIN (-1025 2800) $PN B67
J 2
(-1035 2810);
DISPLAY 0.680851 (-1035 2810);
PAINT MONO (-1035 2810);
FORCEPROP 2 LASTPIN (275 6650) $PN OA10
J 0
(285 6660);
DISPLAY 0.680851 (285 6660);
PAINT MONO (285 6660);
FORCEPROP 2 LASTPIN (275 6500) $PN OA13
J 0
(285 6510);
DISPLAY 0.680851 (285 6510);
PAINT MONO (285 6510);
FORCEPROP 2 LASTPIN (-1025 6650) $PN OB10
J 2
(-1035 6660);
DISPLAY 0.680851 (-1035 6660);
PAINT MONO (-1035 6660);
FORCEPROP 2 LASTPIN (-1025 6500) $PN OB13
J 2
(-1035 6510);
DISPLAY 0.680851 (-1035 6510);
PAINT MONO (-1035 6510);
FORCEPROP 2 LASTPIN (-1025 7000) $PN OB3
J 2
(-1035 7010);
DISPLAY 0.680851 (-1035 7010);
PAINT MONO (-1035 7010);
FORCEPROP 2 LASTPIN (-1025 7050) $PN OB2
J 2
(-1035 7060);
DISPLAY 0.680851 (-1035 7060);
PAINT MONO (-1035 7060);
FORCEPROP 2 LASTPIN (-1025 7100) $PN OB1
J 2
(-1035 7110);
DISPLAY 0.680851 (-1035 7110);
PAINT MONO (-1035 7110);
FORCEPROP 2 LASTPIN (275 5500) $PN A17
J 0
(285 5510);
DISPLAY 0.680851 (285 5510);
PAINT MONO (285 5510);
FORCEPROP 2 LASTPIN (275 5350) $PN A20
J 0
(285 5360);
DISPLAY 0.680851 (285 5360);
PAINT MONO (285 5360);
FORCEPROP 2 LASTPIN (275 5200) $PN A23
J 0
(285 5210);
DISPLAY 0.680851 (285 5210);
PAINT MONO (285 5210);
FORCEPROP 2 LASTPIN (275 5050) $PN A26
J 0
(285 5060);
DISPLAY 0.680851 (285 5060);
PAINT MONO (285 5060);
FORCEPROP 2 LASTPIN (275 4750) $PN A30
J 0
(285 4760);
DISPLAY 0.680851 (285 4760);
PAINT MONO (285 4760);
FORCEPROP 2 LASTPIN (275 4600) $PN A33
J 0
(285 4610);
DISPLAY 0.680851 (285 4610);
PAINT MONO (285 4610);
FORCEPROP 2 LASTPIN (275 4450) $PN A36
J 0
(285 4460);
DISPLAY 0.680851 (285 4460);
PAINT MONO (285 4460);
FORCEPROP 2 LASTPIN (275 4300) $PN A39
J 0
(285 4310);
DISPLAY 0.680851 (285 4310);
PAINT MONO (285 4310);
FORCEPROP 2 LASTPIN (275 3950) $PN A44
J 0
(285 3960);
DISPLAY 0.680851 (285 3960);
PAINT MONO (285 3960);
FORCEPROP 2 LASTPIN (275 3800) $PN A47
J 0
(285 3810);
DISPLAY 0.680851 (285 3810);
PAINT MONO (285 3810);
FORCEPROP 2 LASTPIN (275 3650) $PN A50
J 0
(285 3660);
DISPLAY 0.680851 (285 3660);
PAINT MONO (285 3660);
FORCEPROP 2 LASTPIN (275 3500) $PN A53
J 0
(285 3510);
DISPLAY 0.680851 (285 3510);
PAINT MONO (285 3510);
FORCEPROP 2 LASTPIN (275 3350) $PN A56
J 0
(285 3360);
DISPLAY 0.680851 (285 3360);
PAINT MONO (285 3360);
FORCEPROP 2 LASTPIN (275 3200) $PN A59
J 0
(285 3210);
DISPLAY 0.680851 (285 3210);
PAINT MONO (285 3210);
FORCEPROP 2 LASTPIN (275 3050) $PN A62
J 0
(285 3060);
DISPLAY 0.680851 (285 3060);
PAINT MONO (285 3060);
FORCEPROP 2 LASTPIN (275 2900) $PN A65
J 0
(285 2910);
DISPLAY 0.680851 (285 2910);
PAINT MONO (285 2910);
FORCEPROP 2 LASTPIN (275 5450) $PN A18
J 0
(285 5460);
DISPLAY 0.680851 (285 5460);
PAINT MONO (285 5460);
FORCEPROP 2 LASTPIN (275 5300) $PN A21
J 0
(285 5310);
DISPLAY 0.680851 (285 5310);
PAINT MONO (285 5310);
FORCEPROP 2 LASTPIN (275 5150) $PN A24
J 0
(285 5160);
DISPLAY 0.680851 (285 5160);
PAINT MONO (285 5160);
FORCEPROP 2 LASTPIN (275 5000) $PN A27
J 0
(285 5010);
DISPLAY 0.680851 (285 5010);
PAINT MONO (285 5010);
FORCEPROP 2 LASTPIN (275 4700) $PN A31
J 0
(285 4710);
DISPLAY 0.680851 (285 4710);
PAINT MONO (285 4710);
FORCEPROP 2 LASTPIN (275 4550) $PN A34
J 0
(285 4560);
DISPLAY 0.680851 (285 4560);
PAINT MONO (285 4560);
FORCEPROP 2 LASTPIN (275 4400) $PN A37
J 0
(285 4410);
DISPLAY 0.680851 (285 4410);
PAINT MONO (285 4410);
FORCEPROP 2 LASTPIN (275 4250) $PN A40
J 0
(285 4260);
DISPLAY 0.680851 (285 4260);
PAINT MONO (285 4260);
FORCEPROP 2 LASTPIN (275 3900) $PN A45
J 0
(285 3910);
DISPLAY 0.680851 (285 3910);
PAINT MONO (285 3910);
FORCEPROP 2 LASTPIN (275 3750) $PN A48
J 0
(285 3760);
DISPLAY 0.680851 (285 3760);
PAINT MONO (285 3760);
FORCEPROP 2 LASTPIN (275 3600) $PN A51
J 0
(285 3610);
DISPLAY 0.680851 (285 3610);
PAINT MONO (285 3610);
FORCEPROP 2 LASTPIN (275 3450) $PN A54
J 0
(285 3460);
DISPLAY 0.680851 (285 3460);
PAINT MONO (285 3460);
FORCEPROP 2 LASTPIN (275 3300) $PN A57
J 0
(285 3310);
DISPLAY 0.680851 (285 3310);
PAINT MONO (285 3310);
FORCEPROP 2 LASTPIN (275 3150) $PN A60
J 0
(285 3160);
DISPLAY 0.680851 (285 3160);
PAINT MONO (285 3160);
FORCEPROP 2 LASTPIN (275 3000) $PN A63
J 0
(285 3010);
DISPLAY 0.680851 (285 3010);
PAINT MONO (285 3010);
FORCEPROP 2 LASTPIN (275 2850) $PN A66
J 0
(285 2860);
DISPLAY 0.680851 (285 2860);
PAINT MONO (285 2860);
FORCEPROP 2 LASTPIN (-1025 5850) $PN B10
J 2
(-1035 5860);
DISPLAY 0.680851 (-1035 5860);
PAINT MONO (-1035 5860);
FORCEPROP 2 LASTPIN (275 5800) $PN A11
J 0
(285 5810);
DISPLAY 0.680851 (285 5810);
PAINT MONO (285 5810);
FORCEPROP 2 LASTPIN (275 7100) $PN OA1
J 0
(285 7110);
DISPLAY 0.680851 (285 7110);
PAINT MONO (285 7110);
FORCEPROP 2 LASTPIN (275 7050) $PN OA2
J 0
(285 7060);
DISPLAY 0.680851 (285 7060);
PAINT MONO (285 7060);
FORCEPROP 2 LASTPIN (-1025 5500) $PN B17
J 2
(-1035 5510);
DISPLAY 0.680851 (-1035 5510);
PAINT MONO (-1035 5510);
FORCEPROP 2 LASTPIN (-1025 5350) $PN B20
J 2
(-1035 5360);
DISPLAY 0.680851 (-1035 5360);
PAINT MONO (-1035 5360);
FORCEPROP 2 LASTPIN (-1025 5200) $PN B23
J 2
(-1035 5210);
DISPLAY 0.680851 (-1035 5210);
PAINT MONO (-1035 5210);
FORCEPROP 2 LASTPIN (-1025 5050) $PN B26
J 2
(-1035 5060);
DISPLAY 0.680851 (-1035 5060);
PAINT MONO (-1035 5060);
FORCEPROP 2 LASTPIN (-1025 4750) $PN B30
J 2
(-1035 4760);
DISPLAY 0.680851 (-1035 4760);
PAINT MONO (-1035 4760);
FORCEPROP 2 LASTPIN (-1025 4600) $PN B33
J 2
(-1035 4610);
DISPLAY 0.680851 (-1035 4610);
PAINT MONO (-1035 4610);
FORCEPROP 2 LASTPIN (-1025 4450) $PN B36
J 2
(-1035 4460);
DISPLAY 0.680851 (-1035 4460);
PAINT MONO (-1035 4460);
FORCEPROP 2 LASTPIN (-1025 4300) $PN B39
J 2
(-1035 4310);
DISPLAY 0.680851 (-1035 4310);
PAINT MONO (-1035 4310);
FORCEPROP 2 LASTPIN (-1025 3950) $PN B44
J 2
(-1035 3960);
DISPLAY 0.680851 (-1035 3960);
PAINT MONO (-1035 3960);
FORCEPROP 2 LASTPIN (-1025 3800) $PN B47
J 2
(-1035 3810);
DISPLAY 0.680851 (-1035 3810);
PAINT MONO (-1035 3810);
FORCEPROP 2 LASTPIN (-1025 3650) $PN B50
J 2
(-1035 3660);
DISPLAY 0.680851 (-1035 3660);
PAINT MONO (-1035 3660);
FORCEPROP 2 LASTPIN (-1025 3500) $PN B53
J 2
(-1035 3510);
DISPLAY 0.680851 (-1035 3510);
PAINT MONO (-1035 3510);
FORCEPROP 2 LASTPIN (-1025 3350) $PN B56
J 2
(-1035 3360);
DISPLAY 0.680851 (-1035 3360);
PAINT MONO (-1035 3360);
FORCEPROP 2 LASTPIN (-1025 3200) $PN B59
J 2
(-1035 3210);
DISPLAY 0.680851 (-1035 3210);
PAINT MONO (-1035 3210);
FORCEPROP 2 LASTPIN (-1025 3050) $PN B62
J 2
(-1035 3060);
DISPLAY 0.680851 (-1035 3060);
PAINT MONO (-1035 3060);
FORCEPROP 2 LASTPIN (-1025 2900) $PN B65
J 2
(-1035 2910);
DISPLAY 0.680851 (-1035 2910);
PAINT MONO (-1035 2910);
FORCEPROP 2 LASTPIN (-1025 5450) $PN B18
J 2
(-1035 5460);
DISPLAY 0.680851 (-1035 5460);
PAINT MONO (-1035 5460);
FORCEPROP 2 LASTPIN (-1025 5300) $PN B21
J 2
(-1035 5310);
DISPLAY 0.680851 (-1035 5310);
PAINT MONO (-1035 5310);
FORCEPROP 2 LASTPIN (-1025 5150) $PN B24
J 2
(-1035 5160);
DISPLAY 0.680851 (-1035 5160);
PAINT MONO (-1035 5160);
FORCEPROP 2 LASTPIN (-1025 5000) $PN B27
J 2
(-1035 5010);
DISPLAY 0.680851 (-1035 5010);
PAINT MONO (-1035 5010);
FORCEPROP 2 LASTPIN (-1025 4700) $PN B31
J 2
(-1035 4710);
DISPLAY 0.680851 (-1035 4710);
PAINT MONO (-1035 4710);
FORCEPROP 2 LASTPIN (-1025 4550) $PN B34
J 2
(-1035 4560);
DISPLAY 0.680851 (-1035 4560);
PAINT MONO (-1035 4560);
FORCEPROP 2 LASTPIN (-1025 4400) $PN B37
J 2
(-1035 4410);
DISPLAY 0.680851 (-1035 4410);
PAINT MONO (-1035 4410);
FORCEPROP 2 LASTPIN (-1025 4250) $PN B40
J 2
(-1035 4260);
DISPLAY 0.680851 (-1035 4260);
PAINT MONO (-1035 4260);
FORCEPROP 2 LASTPIN (-1025 3900) $PN B45
J 2
(-1035 3910);
DISPLAY 0.680851 (-1035 3910);
PAINT MONO (-1035 3910);
FORCEPROP 2 LASTPIN (-1025 3750) $PN B48
J 2
(-1035 3760);
DISPLAY 0.680851 (-1035 3760);
PAINT MONO (-1035 3760);
FORCEPROP 2 LASTPIN (-1025 3600) $PN B51
J 2
(-1035 3610);
DISPLAY 0.680851 (-1035 3610);
PAINT MONO (-1035 3610);
FORCEPROP 2 LASTPIN (-1025 3450) $PN B54
J 2
(-1035 3460);
DISPLAY 0.680851 (-1035 3460);
PAINT MONO (-1035 3460);
FORCEPROP 2 LASTPIN (-1025 3300) $PN B57
J 2
(-1035 3310);
DISPLAY 0.680851 (-1035 3310);
PAINT MONO (-1035 3310);
FORCEPROP 2 LASTPIN (-1025 3150) $PN B60
J 2
(-1035 3160);
DISPLAY 0.680851 (-1035 3160);
PAINT MONO (-1035 3160);
FORCEPROP 2 LASTPIN (-1025 3000) $PN B63
J 2
(-1035 3010);
DISPLAY 0.680851 (-1035 3010);
PAINT MONO (-1035 3010);
FORCEPROP 2 LASTPIN (-1025 2850) $PN B66
J 2
(-1035 2860);
DISPLAY 0.680851 (-1035 2860);
PAINT MONO (-1035 2860);
FORCEPROP 2 LASTPIN (275 5850) $PN A10
J 0
(285 5860);
DISPLAY 0.680851 (285 5860);
PAINT MONO (285 5860);
FORCEPROP 2 LASTPIN (-1025 4150) $PN B42
J 2
(-1035 4160);
DISPLAY 0.680851 (-1035 4160);
PAINT MONO (-1035 4160);
FORCEPROP 2 LASTPIN (275 4150) $PN A42
J 0
(285 4160);
DISPLAY 0.680851 (285 4160);
PAINT MONO (285 4160);
FORCEPROP 2 LASTPIN (275 5750) $PN A12
J 0
(285 5760);
DISPLAY 0.680851 (285 5760);
PAINT MONO (285 5760);
FORCEPROP 2 LASTPIN (-1025 2650) $PN B70
J 2
(-1035 2660);
DISPLAY 0.680851 (-1035 2660);
PAINT MONO (-1035 2660);
FORCEPROP 2 LASTPIN (275 2650) $PN A70
J 0
(285 2660);
DISPLAY 0.680851 (285 2660);
PAINT MONO (285 2660);
FORCEPROP 2 LASTPIN (275 6950) $PN OA4
J 0
(285 6960);
DISPLAY 0.680851 (285 6960);
PAINT MONO (285 6960);
FORCEPROP 2 LASTPIN (275 6900) $PN OA5
J 0
(285 6910);
DISPLAY 0.680851 (285 6910);
PAINT MONO (285 6910);
FORCEPROP 2 LASTPIN (275 6450) $PN OA14
J 0
(285 6460);
DISPLAY 0.680851 (285 6460);
PAINT MONO (285 6460);
FORCEPROP 2 LASTPIN (-1025 6450) $PN OB14
J 2
(-1035 6460);
DISPLAY 0.680851 (-1035 6460);
PAINT MONO (-1035 6460);
FORCEPROP 2 LASTPIN (-1025 6700) $PN OB9
J 2
(-1035 6710);
DISPLAY 0.680851 (-1035 6710);
PAINT MONO (-1035 6710);
FORCEPROP 2 LASTPIN (-1025 6750) $PN OB8
J 2
(-1035 6760);
DISPLAY 0.680851 (-1035 6760);
PAINT MONO (-1035 6760);
FORCEPROP 2 LASTPIN (275 6800) $PN OA7
J 0
(285 6810);
DISPLAY 0.680851 (285 6810);
PAINT MONO (285 6810);
FORCEPROP 2 LASTPIN (275 6700) $PN OA9
J 0
(285 6710);
DISPLAY 0.680851 (285 6710);
PAINT MONO (285 6710);
FORCEPROP 2 LASTPIN (275 6750) $PN OA8
J 0
(285 6760);
DISPLAY 0.680851 (285 6760);
PAINT MONO (285 6760);
FORCEPROP 2 LASTPIN (-1025 5650) $PN B14
J 2
(-1035 5660);
DISPLAY 0.680851 (-1035 5660);
PAINT MONO (-1035 5660);
FORCEPROP 2 LASTPIN (275 5650) $PN A14
J 0
(285 5660);
DISPLAY 0.680851 (285 5660);
PAINT MONO (285 5660);
FORCEPROP 2 LASTPIN (-1025 6600) $PN OB11
J 2
(-1035 6610);
DISPLAY 0.680851 (-1035 6610);
PAINT MONO (-1035 6610);
FORCEPROP 2 LASTPIN (275 6600) $PN OA11
J 0
(285 6610);
DISPLAY 0.680851 (285 6610);
PAINT MONO (285 6610);
FORCEPROP 2 LASTPIN (-1025 5600) $PN B15
J 2
(-1035 5610);
DISPLAY 0.680851 (-1035 5610);
PAINT MONO (-1035 5610);
FORCEPROP 2 LASTPIN (275 5600) $PN A15
J 0
(285 5610);
DISPLAY 0.680851 (285 5610);
PAINT MONO (285 5610);
FORCEPROP 2 LASTPIN (-1025 6550) $PN OB12
J 2
(-1035 6560);
DISPLAY 0.680851 (-1035 6560);
PAINT MONO (-1035 6560);
FORCEPROP 2 LASTPIN (275 6550) $PN OA12
J 0
(285 6560);
DISPLAY 0.680851 (285 6560);
PAINT MONO (285 6560);
FORCEPROP 2 LASTPIN (-1025 2750) $PN B68
J 2
(-1035 2760);
DISPLAY 0.680851 (-1035 2760);
PAINT MONO (-1035 2760);
FORCEPROP 2 LASTPIN (-1025 2700) $PN B69
J 2
(-1035 2710);
DISPLAY 0.680851 (-1035 2710);
PAINT MONO (-1035 2710);
FORCEPROP 2 LASTPIN (-1025 6800) $PN OB7
J 2
(-1035 6810);
DISPLAY 0.680851 (-1035 6810);
PAINT MONO (-1035 6810);
FORCEPROP 2 LASTPIN (275 6850) $PN OA6
J 0
(285 6860);
DISPLAY 0.680851 (285 6860);
PAINT MONO (285 6860);
FORCEPROP 2 LASTPIN (275 6000) $PN A7
J 0
(285 6010);
DISPLAY 0.680851 (285 6010);
PAINT MONO (285 6010);
FORCEPROP 2 LASTPIN (275 5950) $PN A8
J 0
(285 5960);
DISPLAY 0.680851 (285 5960);
PAINT MONO (285 5960);
FORCEPROP 2 LASTPIN (275 5900) $PN A9
J 0
(285 5910);
DISPLAY 0.680851 (285 5910);
PAINT MONO (285 5910);
FORCEPROP 2 LASTPIN (275 2750) $PN A68
J 0
(285 2760);
DISPLAY 0.680851 (285 2760);
PAINT MONO (285 2760);
FORCEPROP 2 LASTPIN (275 2700) $PN A69
J 0
(285 2710);
DISPLAY 0.680851 (285 2710);
PAINT MONO (285 2710);
FORCEPROP 2 LASTPIN (275 7000) $PN OA3
J 0
(285 7010);
DISPLAY 0.680851 (285 7010);
PAINT MONO (285 7010);
FORCEPROP 2 LAST SEC_TYPE 
J 0
(-850 7650);
DISPLAY 1.021277 (-850 7650);
DISPLAY INVISIBLE (-850 7650);
FORCEPROP 2 LAST CDS_LIB pure_quanta
J 0
(-375 4725);
DISPLAY INVISIBLE (-375 4725);
FORCEPROP 1 LAST CDS_LMAN_SYM_OUTLINE -500,2475,500,-2475
J 0
(-375 4725);
DISPLAY 0.468085 (-375 4725);
PAINT GREEN (-375 4725);
DISPLAY INVISIBLE (-375 4725);
FORCEPROP 1 LAST NEEDS_NO_SIZE TRUE
J 0
(-375 4725);
DISPLAY 0.723404 (-375 4725);
PAINT GREEN (-375 4725);
DISPLAY INVISIBLE (-375 4725);
FORCEPROP 1 LAST PATH I199
J 0
(-375 4725);
DISPLAY 0.723404 (-375 4725);
PAINT GREEN (-375 4725);
DISPLAY INVISIBLE (-375 4725);
FORCEPROP 2 LAST SEC 1
J 0
(-850 7650);
DISPLAY 0.680851 (-850 7650);
PAINT MONO (-850 7650);
DISPLAY INVISIBLE (-850 7650);
FORCEADD Q_RES..2
(-4325 1725);
FORCEPROP 1 LAST PART_NUMBER CS24702FB06
J 0
(-4285 1600);
DISPLAY 0.787234 (-4285 1600);
DISPLAY INVISIBLE (-4285 1600);
FORCEPROP 1 LAST VALUE 4.7K
J 0
(-4280 1800);
DISPLAY 0.787234 (-4280 1800);
FORCEPROP 1 LAST WATTAGE 1/16W
J 0
(-4285 1700);
DISPLAY 0.787234 (-4285 1700);
FORCEPROP 1 LAST TOLERANCE 1%
J 0
(-4280 1750);
DISPLAY 0.787234 (-4280 1750);
FORCEPROP 1 LAST MATERIAL CHIP
J 0
(-4285 1650);
DISPLAY 0.787234 (-4285 1650);
FORCEPROP 1 LAST PACK_TYPE 0402LF
J 0
(-4285 1550);
DISPLAY 0.787234 (-4285 1550);
FORCEPROP 1 LAST $LOCATION R410
J 0
(-4280 1850);
DISPLAY 0.978723 (-4280 1850);
FORCEPROP 1 LASTPIN (-4325 1825) $PN 1
J 0
(-4320 1787);
DISPLAY 0.787234 (-4320 1787);
FORCEPROP 1 LASTPIN (-4325 1625) $PN 2
J 0
(-4320 1635);
DISPLAY 0.787234 (-4320 1635);
FORCEPROP 2 LAST CDS_LIB pure_quanta
J 0
(-4325 1725);
PAINT MONO (-4325 1725);
DISPLAY INVISIBLE (-4325 1725);
FORCEPROP 1 LAST PATH I2
J 0
(-4275 1900);
DISPLAY 0.978723 (-4275 1900);
PAINT WHITE (-4275 1900);
DISPLAY INVISIBLE (-4275 1900);
FORCEPROP 2 LAST CDS_LOCATION R410
J 0
(-4275 1950);
DISPLAY 1.021277 (-4275 1950);
DISPLAY INVISIBLE (-4275 1950);
FORCEPROP 2 LAST $SEC 1
J 0
(-4275 1950);
DISPLAY 0.680851 (-4275 1950);
PAINT MONO (-4275 1950);
DISPLAY INVISIBLE (-4275 1950);
FORCEPROP 2 LAST CDS_SEC 1
J 0
(-4275 1950);
DISPLAY 1.021277 (-4275 1950);
DISPLAY INVISIBLE (-4275 1950);
FORCEADD TAP..1
R 2
(-1750 3350);
FORCEPROP 3 LASTPIN (-1700 3350) SIG_NAME P5E_CPU0_PE1_TX_C_DP<12>
J 0
(-1690 3360);
DISPLAY 0.659574 (-1690 3360);
PAINT MONO (-1690 3360);
DISPLAY INVISIBLE (-1690 3360);
FORCEPROP 1 LASTPIN (-1700 3350) BN 12
J 2
(-1688 3358);
DISPLAY 0.680851 (-1688 3358);
PAINT GREEN (-1688 3358);
FORCEPROP 2 LAST CDS_LIB standard
J 0
(-1750 3350);
PAINT MONO (-1750 3350);
DISPLAY INVISIBLE (-1750 3350);
FORCEPROP 1 LAST BODY_TYPE PLUMBING
J 2
(-1750 3400);
DISPLAY 0.872340 (-1750 3400);
PAINT GREEN (-1750 3400);
DISPLAY INVISIBLE (-1750 3400);
FORCEPROP 1 LAST HDL_TAP TRUE
J 2
(-2075 3225);
DISPLAY 0.872340 (-2075 3225);
PAINT GREEN (-2075 3225);
DISPLAY INVISIBLE (-2075 3225);
FORCEPROP 1 LAST PATH I20
J 2
(-1748 3350);
DISPLAY 0.872340 (-1748 3350);
PAINT GREEN (-1748 3350);
DISPLAY INVISIBLE (-1748 3350);
FORCEADD TAP..1
R 2
(-1600 5500);
FORCEPROP 3 LASTPIN (-1550 5500) SIG_NAME P5E_CPU0_PE1_TX_C_DN<0>
J 0
(-1540 5510);
DISPLAY 0.659574 (-1540 5510);
PAINT MONO (-1540 5510);
DISPLAY INVISIBLE (-1540 5510);
FORCEPROP 1 LASTPIN (-1550 5500) BN 0
J 2
(-1538 5508);
DISPLAY 0.680851 (-1538 5508);
PAINT GREEN (-1538 5508);
FORCEPROP 2 LAST CDS_LIB standard
J 0
(-1600 5500);
DISPLAY INVISIBLE (-1600 5500);
FORCEPROP 1 LAST BODY_TYPE PLUMBING
J 2
(-1600 5550);
DISPLAY 0.872340 (-1600 5550);
PAINT GREEN (-1600 5550);
DISPLAY INVISIBLE (-1600 5550);
FORCEPROP 1 LAST HDL_TAP TRUE
J 2
(-1925 5375);
DISPLAY 0.872340 (-1925 5375);
PAINT GREEN (-1925 5375);
DISPLAY INVISIBLE (-1925 5375);
FORCEPROP 1 LAST PATH I202
J 2
(-1598 5500);
DISPLAY 0.872340 (-1598 5500);
PAINT GREEN (-1598 5500);
DISPLAY INVISIBLE (-1598 5500);
FORCEADD TAP..1
R 2
(-1750 5450);
FORCEPROP 3 LASTPIN (-1700 5450) SIG_NAME P5E_CPU0_PE1_TX_C_DP<0>
J 0
(-1690 5460);
DISPLAY 0.659574 (-1690 5460);
PAINT MONO (-1690 5460);
DISPLAY INVISIBLE (-1690 5460);
FORCEPROP 1 LASTPIN (-1700 5450) BN 0
J 2
(-1688 5458);
DISPLAY 0.680851 (-1688 5458);
PAINT GREEN (-1688 5458);
FORCEPROP 2 LAST CDS_LIB standard
J 0
(-1750 5450);
DISPLAY INVISIBLE (-1750 5450);
FORCEPROP 1 LAST BODY_TYPE PLUMBING
J 2
(-1750 5500);
DISPLAY 0.872340 (-1750 5500);
PAINT GREEN (-1750 5500);
DISPLAY INVISIBLE (-1750 5500);
FORCEPROP 1 LAST HDL_TAP TRUE
J 2
(-2075 5325);
DISPLAY 0.872340 (-2075 5325);
PAINT GREEN (-2075 5325);
DISPLAY INVISIBLE (-2075 5325);
FORCEPROP 1 LAST PATH I203
J 2
(-1748 5450);
DISPLAY 0.872340 (-1748 5450);
PAINT GREEN (-1748 5450);
DISPLAY INVISIBLE (-1748 5450);
FORCEADD TAP..1
(900 5450);
FORCEPROP 3 LASTPIN (850 5450) SIG_NAME P5E_CPU0_PE1_RX_DP<0>
J 0
(860 5460);
DISPLAY 0.659574 (860 5460);
PAINT MONO (860 5460);
DISPLAY INVISIBLE (860 5460);
FORCEPROP 1 LASTPIN (850 5450) BN 0
J 0
(838 5458);
DISPLAY 0.680851 (838 5458);
PAINT GREEN (838 5458);
FORCEPROP 2 LAST CDS_LIB standard
J 0
(900 5450);
PAINT MONO (900 5450);
DISPLAY INVISIBLE (900 5450);
FORCEPROP 1 LAST BODY_TYPE PLUMBING
J 0
(900 5500);
DISPLAY 0.872340 (900 5500);
PAINT GREEN (900 5500);
DISPLAY INVISIBLE (900 5500);
FORCEPROP 1 LAST HDL_TAP TRUE
J 0
(1225 5325);
DISPLAY 0.872340 (1225 5325);
DISPLAY INVISIBLE (1225 5325);
FORCEPROP 1 LAST PATH I205
J 0
(898 5450);
DISPLAY 0.872340 (898 5450);
PAINT GREEN (898 5450);
DISPLAY INVISIBLE (898 5450);
FORCEADD TAP..1
(750 5500);
FORCEPROP 3 LASTPIN (700 5500) SIG_NAME P5E_CPU0_PE1_RX_DN<0>
J 0
(710 5510);
DISPLAY 0.659574 (710 5510);
PAINT MONO (710 5510);
DISPLAY INVISIBLE (710 5510);
FORCEPROP 1 LASTPIN (700 5500) BN 0
J 0
(688 5508);
DISPLAY 0.680851 (688 5508);
PAINT GREEN (688 5508);
FORCEPROP 2 LAST CDS_LIB standard
J 0
(750 5500);
PAINT MONO (750 5500);
DISPLAY INVISIBLE (750 5500);
FORCEPROP 1 LAST BODY_TYPE PLUMBING
J 0
(750 5550);
DISPLAY 0.872340 (750 5550);
PAINT GREEN (750 5550);
DISPLAY INVISIBLE (750 5550);
FORCEPROP 1 LAST HDL_TAP TRUE
J 0
(1075 5375);
DISPLAY 0.872340 (1075 5375);
PAINT GREEN (1075 5375);
DISPLAY INVISIBLE (1075 5375);
FORCEPROP 1 LAST PATH I206
J 0
(748 5500);
DISPLAY 0.872340 (748 5500);
PAINT GREEN (748 5500);
DISPLAY INVISIBLE (748 5500);
FORCEADD TAP..1
R 2
(-1750 3650);
FORCEPROP 3 LASTPIN (-1700 3650) SIG_NAME P5E_CPU0_PE1_TX_C_DP<10>
J 0
(-1690 3660);
DISPLAY 0.659574 (-1690 3660);
PAINT MONO (-1690 3660);
DISPLAY INVISIBLE (-1690 3660);
FORCEPROP 1 LASTPIN (-1700 3650) BN 10
J 2
(-1688 3658);
DISPLAY 0.680851 (-1688 3658);
PAINT GREEN (-1688 3658);
FORCEPROP 2 LAST CDS_LIB standard
J 0
(-1750 3650);
PAINT MONO (-1750 3650);
DISPLAY INVISIBLE (-1750 3650);
FORCEPROP 1 LAST BODY_TYPE PLUMBING
J 2
(-1750 3700);
DISPLAY 0.872340 (-1750 3700);
PAINT GREEN (-1750 3700);
DISPLAY INVISIBLE (-1750 3700);
FORCEPROP 1 LAST HDL_TAP TRUE
J 2
(-2075 3525);
DISPLAY 0.872340 (-2075 3525);
PAINT GREEN (-2075 3525);
DISPLAY INVISIBLE (-2075 3525);
FORCEPROP 1 LAST PATH I21
J 2
(-1748 3650);
DISPLAY 0.872340 (-1748 3650);
PAINT GREEN (-1748 3650);
DISPLAY INVISIBLE (-1748 3650);
FORCEADD OFFPAGE..1
(-2800 5475);
FORCEPROP 2 LAST $XR0 174 
J 0
(-3052 5475);
DISPLAY 0.638298 (-3052 5475);
PAINT MONO (-3052 5475);
FORCEPROP 2 LAST CDS_LIB standard
J 0
(-2800 5475);
DISPLAY INVISIBLE (-2800 5475);
FORCEPROP 1 LAST OFFPAGE TRUE
J 0
(-2475 5350);
DISPLAY 0.872340 (-2475 5350);
PAINT GREEN (-2475 5350);
DISPLAY INVISIBLE (-2475 5350);
FORCEPROP 1 LAST COMMENT_BODY TRUE
J 0
(-2675 5375);
DISPLAY 0.872340 (-2675 5375);
PAINT GREEN (-2675 5375);
DISPLAY INVISIBLE (-2675 5375);
FORCEPROP 2 LAST PATH I211
J 0
(-3050 5525);
DISPLAY 1.021277 (-3050 5525);
DISPLAY INVISIBLE (-3050 5525);
FORCEADD Q_RES..1
(-775 1625);
FORCEPROP 1 LAST PART_NUMBER CS21002FB06
J 0
(-825 1675);
DISPLAY 0.510638 (-825 1675);
DISPLAY INVISIBLE (-825 1675);
FORCEPROP 1 LAST PACK_TYPE 0402LF
J 0
(-825 1725);
DISPLAY 0.510638 (-825 1725);
FORCEPROP 1 LAST TOLERANCE 1%
J 0
(-525 1625);
DISPLAY 0.638298 (-525 1625);
FORCEPROP 1 LAST WATTAGE 1/16W
J 2
(-525 1725);
DISPLAY 0.510638 (-525 1725);
FORCEPROP 1 LAST VALUE 1K
J 2
(-575 1625);
DISPLAY 0.638298 (-575 1625);
FORCEPROP 1 LAST MATERIAL CHIP
J 0
(-400 1625);
DISPLAY 0.638298 (-400 1625);
FORCEPROP 1 LAST LOCATION R423
J 0
(-975 1625);
DISPLAY 0.638298 (-975 1625);
FORCEPROP 1 LASTPIN (-875 1625) $PN 1
J 0
(-863 1637);
DISPLAY 0.787234 (-863 1637);
PAINT MONO (-863 1637);
FORCEPROP 1 LASTPIN (-675 1625) $PN 2
J 0
(-713 1637);
DISPLAY 0.787234 (-713 1637);
PAINT MONO (-713 1637);
FORCEPROP 2 LAST CDS_LIB pure_quanta
J 0
(-775 1625);
DISPLAY INVISIBLE (-775 1625);
FORCEPROP 1 LAST PATH I212
J 0
(-825 1775);
DISPLAY 0.978723 (-825 1775);
PAINT WHITE (-825 1775);
DISPLAY INVISIBLE (-825 1775);
FORCEPROP 0 LAST $SEC 1
J 0
(-525 1750);
DISPLAY 0.680851 (-525 1750);
PAINT MONO (-525 1750);
DISPLAY INVISIBLE (-525 1750);
FORCEPROP 0 LAST CDS_SEC 1
J 0
(-525 1750);
DISPLAY 1.021277 (-525 1750);
DISPLAY INVISIBLE (-525 1750);
FORCEADD OFFPAGE..5
(-2025 1625);
FORCEPROP 2 LAST $XR1 213 
J 0
(-2430 1625);
DISPLAY 0.638298 (-2430 1625);
PAINT MONO (-2430 1625);
FORCEPROP 2 LAST $XR0 153 
J 0
(-2310 1625);
DISPLAY 0.638298 (-2310 1625);
PAINT MONO (-2310 1625);
FORCEPROP 2 LAST CDS_LIB standard
J 0
(-2025 1625);
PAINT MONO (-2025 1625);
DISPLAY INVISIBLE (-2025 1625);
FORCEPROP 1 LAST OFFPAGE TRUE
J 0
(-1700 1500);
DISPLAY 0.872340 (-1700 1500);
PAINT GREEN (-1700 1500);
DISPLAY INVISIBLE (-1700 1500);
FORCEPROP 1 LAST COMMENT_BODY TRUE
J 0
(-1925 1550);
DISPLAY 0.872340 (-1925 1550);
PAINT GREEN (-1925 1550);
DISPLAY INVISIBLE (-1925 1550);
FORCEPROP 2 LAST PATH I213
J 0
(-2300 1675);
DISPLAY 1.021277 (-2300 1675);
DISPLAY INVISIBLE (-2300 1675);
FORCEADD Q_RES..1
(-775 1450);
FORCEPROP 1 LAST PART_NUMBER CS31002FB08
J 0
(-950 1525);
DISPLAY 0.510638 (-950 1525);
DISPLAY INVISIBLE (-950 1525);
FORCEPROP 1 LAST MATERIAL CHIP
J 0
(-500 1450);
DISPLAY 0.510638 (-500 1450);
FORCEPROP 1 LAST TOLERANCE 1%
J 0
(-575 1450);
DISPLAY 0.510638 (-575 1450);
FORCEPROP 1 LAST VALUE 10K
J 2
(-600 1450);
DISPLAY 0.510638 (-600 1450);
FORCEPROP 1 LAST LOCATION R422
J 0
(-975 1450);
DISPLAY 0.638298 (-975 1450);
FORCEPROP 1 LASTPIN (-875 1450) $PN 1
J 0
(-863 1462);
DISPLAY 0.787234 (-863 1462);
PAINT MONO (-863 1462);
FORCEPROP 1 LASTPIN (-675 1450) $PN 2
J 0
(-713 1462);
DISPLAY 0.787234 (-713 1462);
PAINT MONO (-713 1462);
FORCEPROP 2 LAST CDS_LIB pure_quanta
J 0
(-775 1450);
DISPLAY INVISIBLE (-775 1450);
FORCEPROP 1 LAST PACK_TYPE 0402LF
J 0
(-950 1575);
DISPLAY 0.510638 (-950 1575);
DISPLAY INVISIBLE (-950 1575);
FORCEPROP 1 LAST WATTAGE 1/16W
J 2
(-575 1575);
DISPLAY 0.510638 (-575 1575);
DISPLAY INVISIBLE (-575 1575);
FORCEPROP 1 LAST PATH I215
J 0
(-825 1600);
DISPLAY 0.978723 (-825 1600);
PAINT WHITE (-825 1600);
DISPLAY INVISIBLE (-825 1600);
FORCEPROP 0 LAST $SEC 1
J 0
(-975 1500);
DISPLAY 0.680851 (-975 1500);
PAINT MONO (-975 1500);
DISPLAY INVISIBLE (-975 1500);
FORCEPROP 0 LAST CDS_SEC 1
J 0
(-975 1500);
DISPLAY 1.021277 (-975 1500);
DISPLAY INVISIBLE (-975 1500);
FORCEADD Q_RES..1
(-775 1800);
FORCEPROP 1 LAST PART_NUMBER CS31002FB08
J 0
(-950 1875);
DISPLAY 0.510638 (-950 1875);
DISPLAY INVISIBLE (-950 1875);
FORCEPROP 1 LAST MATERIAL CHIP
J 0
(-500 1800);
DISPLAY 0.510638 (-500 1800);
FORCEPROP 1 LAST TOLERANCE 1%
J 0
(-575 1800);
DISPLAY 0.510638 (-575 1800);
FORCEPROP 1 LAST VALUE 10K
J 2
(-600 1800);
DISPLAY 0.510638 (-600 1800);
FORCEPROP 1 LAST LOCATION R421
J 0
(-975 1800);
DISPLAY 0.638298 (-975 1800);
FORCEPROP 1 LASTPIN (-875 1800) $PN 1
J 0
(-863 1812);
DISPLAY 0.787234 (-863 1812);
PAINT MONO (-863 1812);
FORCEPROP 1 LASTPIN (-675 1800) $PN 2
J 0
(-713 1812);
DISPLAY 0.787234 (-713 1812);
PAINT MONO (-713 1812);
FORCEPROP 1 LAST PACK_TYPE 0402LF
J 0
(-950 1925);
DISPLAY 0.510638 (-950 1925);
DISPLAY INVISIBLE (-950 1925);
FORCEPROP 1 LAST WATTAGE 1/16W
J 2
(-575 1925);
DISPLAY 0.510638 (-575 1925);
DISPLAY INVISIBLE (-575 1925);
FORCEPROP 2 LAST CDS_LIB pure_quanta
J 0
(-775 1800);
DISPLAY INVISIBLE (-775 1800);
FORCEPROP 1 LAST PATH I217
J 0
(-825 1950);
DISPLAY 0.978723 (-825 1950);
PAINT WHITE (-825 1950);
DISPLAY INVISIBLE (-825 1950);
FORCEPROP 0 LAST $SEC 1
J 0
(-975 1850);
DISPLAY 0.680851 (-975 1850);
PAINT MONO (-975 1850);
DISPLAY INVISIBLE (-975 1850);
FORCEPROP 0 LAST CDS_SEC 1
J 0
(-975 1850);
DISPLAY 1.021277 (-975 1850);
DISPLAY INVISIBLE (-975 1850);
FORCEADD Q_RES..1
(-775 1975);
FORCEPROP 1 LAST PART_NUMBER CS21002FB06
J 0
(-825 2025);
DISPLAY 0.510638 (-825 2025);
DISPLAY INVISIBLE (-825 2025);
FORCEPROP 1 LAST VALUE 1K
J 2
(-575 1975);
DISPLAY 0.638298 (-575 1975);
FORCEPROP 1 LAST TOLERANCE 1%
J 0
(-525 1975);
DISPLAY 0.638298 (-525 1975);
FORCEPROP 1 LAST WATTAGE 1/16W
J 2
(-525 2075);
DISPLAY 0.510638 (-525 2075);
FORCEPROP 1 LAST PACK_TYPE 0402LF
J 0
(-825 2075);
DISPLAY 0.510638 (-825 2075);
FORCEPROP 1 LAST MATERIAL CHIP
J 0
(-400 1975);
DISPLAY 0.638298 (-400 1975);
FORCEPROP 1 LAST LOCATION R420
J 0
(-975 1975);
DISPLAY 0.638298 (-975 1975);
FORCEPROP 1 LASTPIN (-875 1975) $PN 1
J 0
(-863 1987);
DISPLAY 0.787234 (-863 1987);
PAINT MONO (-863 1987);
FORCEPROP 1 LASTPIN (-675 1975) $PN 2
J 0
(-713 1987);
DISPLAY 0.787234 (-713 1987);
PAINT MONO (-713 1987);
FORCEPROP 2 LAST CDS_LIB pure_quanta
J 0
(-775 1975);
DISPLAY INVISIBLE (-775 1975);
FORCEPROP 1 LAST PATH I218
J 0
(-825 2125);
DISPLAY 0.978723 (-825 2125);
PAINT WHITE (-825 2125);
DISPLAY INVISIBLE (-825 2125);
FORCEPROP 0 LAST $SEC 1
J 0
(-525 2100);
DISPLAY 0.680851 (-525 2100);
PAINT MONO (-525 2100);
DISPLAY INVISIBLE (-525 2100);
FORCEPROP 0 LAST CDS_SEC 1
J 0
(-525 2100);
DISPLAY 1.021277 (-525 2100);
DISPLAY INVISIBLE (-525 2100);
FORCEADD OFFPAGE..5
(-4075 7050);
FORCEPROP 2 LAST $XR1 214 
J 0
(-4450 7050);
DISPLAY 0.638298 (-4450 7050);
PAINT MONO (-4450 7050);
FORCEPROP 2 LAST $XR0 153 
J 0
(-4330 7050);
DISPLAY 0.638298 (-4330 7050);
PAINT MONO (-4330 7050);
FORCEPROP 2 LAST CDS_LIB standard
J 0
(-4075 7050);
DISPLAY INVISIBLE (-4075 7050);
FORCEPROP 1 LAST OFFPAGE TRUE
J 0
(-3750 6925);
DISPLAY 0.872340 (-3750 6925);
PAINT GREEN (-3750 6925);
DISPLAY INVISIBLE (-3750 6925);
FORCEPROP 1 LAST COMMENT_BODY TRUE
J 0
(-3975 6975);
DISPLAY 0.872340 (-3975 6975);
PAINT GREEN (-3975 6975);
DISPLAY INVISIBLE (-3975 6975);
FORCEPROP 2 LAST PATH I219
J 0
(-4025 7125);
DISPLAY 1.021277 (-4025 7125);
DISPLAY INVISIBLE (-4025 7125);
FORCEADD Q_RES..1
(1750 5950);
FORCEPROP 1 LAST PART_NUMBER CS12002FB06
J 0
(1875 5975);
DISPLAY 0.404255 (1875 5975);
DISPLAY INVISIBLE (1875 5975);
FORCEPROP 1 LAST MATERIAL CHIP
J 0
(2225 5975);
DISPLAY 0.404255 (2225 5975);
FORCEPROP 1 LAST TOLERANCE 1%
J 0
(1975 5950);
DISPLAY 0.510638 (1975 5950);
FORCEPROP 1 LAST VALUE 200
J 2
(1950 5950);
DISPLAY 0.510638 (1950 5950);
FORCEPROP 1 LAST PACK_TYPE 0402LF
J 0
(2075 5950);
DISPLAY 0.510638 (2075 5950);
FORCEPROP 1 LAST WATTAGE 1/16W
J 2
(2200 5975);
DISPLAY 0.404255 (2200 5975);
FORCEPROP 1 LAST LOCATION R425
J 0
(1550 5950);
DISPLAY 0.638298 (1550 5950);
FORCEPROP 1 LASTPIN (1650 5950) $PN 1
J 0
(1662 5962);
DISPLAY 0.787234 (1662 5962);
FORCEPROP 1 LASTPIN (1850 5950) $PN 2
J 0
(1812 5962);
DISPLAY 0.787234 (1812 5962);
FORCEPROP 2 LAST CDS_LIB pure_quanta
J 0
(1750 5950);
PAINT MONO (1750 5950);
DISPLAY INVISIBLE (1750 5950);
FORCEPROP 1 LAST PATH I220
J 0
(1700 6100);
DISPLAY 0.978723 (1700 6100);
PAINT WHITE (1700 6100);
DISPLAY INVISIBLE (1700 6100);
FORCEPROP 1 LAST LOCATION R425
J 0
(1700 6150);
DISPLAY 1.021277 (1700 6150);
DISPLAY INVISIBLE (1700 6150);
FORCEPROP 2 LAST $SEC 1
J 0
(1700 6150);
DISPLAY 0.680851 (1700 6150);
PAINT MONO (1700 6150);
DISPLAY INVISIBLE (1700 6150);
FORCEPROP 2 LAST CDS_SEC 1
J 0
(1700 6150);
DISPLAY 1.021277 (1700 6150);
DISPLAY INVISIBLE (1700 6150);
FORCEADD UNIVERSAL_GND..1
(-1375 2500);
FORCEPROP 3 LASTPIN (-1375 2550) SIG_NAME GND\g
J 0
(-1365 2560);
DISPLAY 0.659574 (-1365 2560);
PAINT MONO (-1365 2560);
DISPLAY INVISIBLE (-1365 2560);
FORCEPROP 2 LAST CDS_LIB logical_power
J 0
(-1375 2500);
PAINT MONO (-1375 2500);
DISPLAY INVISIBLE (-1375 2500);
FORCEPROP 1 LAST HDL_POWER GND
J 1
(-1350 2425);
DISPLAY 0.872340 (-1350 2425);
PAINT GREEN (-1350 2425);
DISPLAY INVISIBLE (-1350 2425);
FORCEPROP 1 LAST PATH I25
J 0
(-1300 2500);
DISPLAY 0.872340 (-1300 2500);
PAINT AQUA (-1300 2500);
DISPLAY INVISIBLE (-1300 2500);
FORCEPROP 2 LAST ROOM IO_SLOT
J 1
(-1600 2575);
DISPLAY 0.744681 (-1600 2575);
DISPLAY INVISIBLE (-1600 2575);
FORCEADD TAP..1
R 2
(-1600 3000);
FORCEPROP 3 LASTPIN (-1550 3000) SIG_NAME P5E_CPU0_PE1_TX_C_DN<14>
J 0
(-1540 3010);
DISPLAY 0.659574 (-1540 3010);
PAINT MONO (-1540 3010);
DISPLAY INVISIBLE (-1540 3010);
FORCEPROP 1 LASTPIN (-1550 3000) BN 14
J 2
(-1538 3008);
DISPLAY 0.680851 (-1538 3008);
PAINT GREEN (-1538 3008);
FORCEPROP 2 LAST CDS_LIB standard
J 0
(-1600 3000);
PAINT MONO (-1600 3000);
DISPLAY INVISIBLE (-1600 3000);
FORCEPROP 1 LAST BODY_TYPE PLUMBING
J 2
(-1600 3050);
DISPLAY 0.872340 (-1600 3050);
PAINT GREEN (-1600 3050);
DISPLAY INVISIBLE (-1600 3050);
FORCEPROP 1 LAST HDL_TAP TRUE
J 2
(-1925 2875);
DISPLAY 0.872340 (-1925 2875);
PAINT GREEN (-1925 2875);
DISPLAY INVISIBLE (-1925 2875);
FORCEPROP 1 LAST PATH I28
J 2
(-1598 3000);
DISPLAY 0.872340 (-1598 3000);
PAINT GREEN (-1598 3000);
DISPLAY INVISIBLE (-1598 3000);
FORCEADD UNIVERSAL_GND..1
(-3850 1500);
FORCEPROP 3 LASTPIN (-3850 1550) SIG_NAME GND\g
J 0
(-3840 1560);
DISPLAY 0.659574 (-3840 1560);
PAINT MONO (-3840 1560);
DISPLAY INVISIBLE (-3840 1560);
FORCEPROP 2 LAST CDS_LIB logical_power
J 0
(-3850 1500);
PAINT MONO (-3850 1500);
DISPLAY INVISIBLE (-3850 1500);
FORCEPROP 1 LAST HDL_POWER GND
J 1
(-3825 1425);
DISPLAY 0.872340 (-3825 1425);
PAINT GREEN (-3825 1425);
DISPLAY INVISIBLE (-3825 1425);
FORCEPROP 1 LAST PATH I3
J 0
(-3775 1500);
DISPLAY 0.872340 (-3775 1500);
PAINT AQUA (-3775 1500);
DISPLAY INVISIBLE (-3775 1500);
FORCEPROP 2 LAST ROOM IO_SLOT
J 1
(-4075 1575);
DISPLAY 0.744681 (-4075 1575);
DISPLAY INVISIBLE (-4075 1575);
FORCEADD TAP..1
R 2
(-1600 3300);
FORCEPROP 3 LASTPIN (-1550 3300) SIG_NAME P5E_CPU0_PE1_TX_C_DN<12>
J 0
(-1540 3310);
DISPLAY 0.659574 (-1540 3310);
PAINT MONO (-1540 3310);
DISPLAY INVISIBLE (-1540 3310);
FORCEPROP 1 LASTPIN (-1550 3300) BN 12
J 2
(-1538 3308);
DISPLAY 0.680851 (-1538 3308);
PAINT GREEN (-1538 3308);
FORCEPROP 2 LAST CDS_LIB standard
J 0
(-1600 3300);
PAINT MONO (-1600 3300);
DISPLAY INVISIBLE (-1600 3300);
FORCEPROP 1 LAST BODY_TYPE PLUMBING
J 2
(-1600 3350);
DISPLAY 0.872340 (-1600 3350);
PAINT GREEN (-1600 3350);
DISPLAY INVISIBLE (-1600 3350);
FORCEPROP 1 LAST HDL_TAP TRUE
J 2
(-1925 3175);
DISPLAY 0.872340 (-1925 3175);
PAINT GREEN (-1925 3175);
DISPLAY INVISIBLE (-1925 3175);
FORCEPROP 1 LAST PATH I30
J 2
(-1598 3300);
DISPLAY 0.872340 (-1598 3300);
PAINT GREEN (-1598 3300);
DISPLAY INVISIBLE (-1598 3300);
FORCEADD TAP..1
R 2
(-1600 3600);
FORCEPROP 3 LASTPIN (-1550 3600) SIG_NAME P5E_CPU0_PE1_TX_C_DN<10>
J 0
(-1540 3610);
DISPLAY 0.659574 (-1540 3610);
PAINT MONO (-1540 3610);
DISPLAY INVISIBLE (-1540 3610);
FORCEPROP 1 LASTPIN (-1550 3600) BN 10
J 2
(-1538 3608);
DISPLAY 0.680851 (-1538 3608);
PAINT GREEN (-1538 3608);
FORCEPROP 2 LAST CDS_LIB standard
J 0
(-1600 3600);
PAINT MONO (-1600 3600);
DISPLAY INVISIBLE (-1600 3600);
FORCEPROP 1 LAST BODY_TYPE PLUMBING
J 2
(-1600 3650);
DISPLAY 0.872340 (-1600 3650);
PAINT GREEN (-1600 3650);
DISPLAY INVISIBLE (-1600 3650);
FORCEPROP 1 LAST HDL_TAP TRUE
J 2
(-1925 3475);
DISPLAY 0.872340 (-1925 3475);
PAINT GREEN (-1925 3475);
DISPLAY INVISIBLE (-1925 3475);
FORCEPROP 1 LAST PATH I32
J 2
(-1598 3600);
DISPLAY 0.872340 (-1598 3600);
PAINT GREEN (-1598 3600);
DISPLAY INVISIBLE (-1598 3600);
FORCEADD UNIVERSAL_GND..1
(-4675 4325);
FORCEPROP 3 LASTPIN (-4675 4375) SIG_NAME GND\g
J 0
(-4665 4385);
DISPLAY 0.659574 (-4665 4385);
PAINT MONO (-4665 4385);
DISPLAY INVISIBLE (-4665 4385);
FORCEPROP 2 LAST CDS_LIB logical_power
J 0
(-4675 4325);
DISPLAY INVISIBLE (-4675 4325);
FORCEPROP 1 LAST HDL_POWER GND
J 1
(-4650 4250);
DISPLAY 0.872340 (-4650 4250);
PAINT GREEN (-4650 4250);
DISPLAY INVISIBLE (-4650 4250);
FORCEPROP 1 LAST PATH I34
J 0
(-4600 4325);
DISPLAY 0.872340 (-4600 4325);
PAINT AQUA (-4600 4325);
DISPLAY INVISIBLE (-4600 4325);
FORCEADD Q_RES..1
(-4250 4425);
FORCEPROP 1 LAST PART_NUMBER CS41002FB09
J 0
(-4425 4475);
DISPLAY 0.510638 (-4425 4475);
DISPLAY INVISIBLE (-4425 4475);
FORCEPROP 1 LAST PACK_TYPE 0402LF
J 0
(-4425 4525);
DISPLAY 0.510638 (-4425 4525);
FORCEPROP 1 LAST TOLERANCE 1%
J 0
(-4025 4425);
DISPLAY 0.510638 (-4025 4425);
FORCEPROP 1 LAST MATERIAL CHIP
J 0
(-3925 4425);
DISPLAY 0.510638 (-3925 4425);
FORCEPROP 1 LAST VALUE 100K
J 2
(-4050 4425);
DISPLAY 0.510638 (-4050 4425);
FORCEPROP 1 LAST WATTAGE 1/16W
J 2
(-4050 4525);
DISPLAY 0.510638 (-4050 4525);
FORCEPROP 1 LAST $LOCATION R3132
J 0
(-4525 4425);
DISPLAY 0.787234 (-4525 4425);
FORCEPROP 1 LASTPIN (-4350 4425) $PN 1
J 0
(-4338 4437);
DISPLAY 0.787234 (-4338 4437);
PAINT MONO (-4338 4437);
FORCEPROP 1 LASTPIN (-4150 4425) $PN 2
J 0
(-4188 4437);
DISPLAY 0.787234 (-4188 4437);
PAINT MONO (-4188 4437);
FORCEPROP 2 LAST CDS_LIB pure_quanta
J 0
(-4250 4425);
DISPLAY INVISIBLE (-4250 4425);
FORCEPROP 1 LAST PATH I35
J 0
(-4300 4575);
DISPLAY 0.978723 (-4300 4575);
PAINT WHITE (-4300 4575);
DISPLAY INVISIBLE (-4300 4575);
FORCEPROP 0 LAST CDS_LOCATION R3132
J 0
(-4050 4550);
DISPLAY 1.021277 (-4050 4550);
DISPLAY INVISIBLE (-4050 4550);
FORCEPROP 0 LAST $SEC 1
J 0
(-4050 4550);
DISPLAY 0.680851 (-4050 4550);
PAINT MONO (-4050 4550);
DISPLAY INVISIBLE (-4050 4550);
FORCEPROP 0 LAST CDS_SEC 1
J 0
(-4050 4550);
DISPLAY 1.021277 (-4050 4550);
DISPLAY INVISIBLE (-4050 4550);
FORCEADD Q_RES..1
(-4250 4625);
FORCEPROP 1 LAST PART_NUMBER CS31002FB08
J 0
(-4425 4700);
DISPLAY 0.510638 (-4425 4700);
DISPLAY INVISIBLE (-4425 4700);
FORCEPROP 1 LAST VALUE 10K
J 2
(-4075 4625);
DISPLAY 0.510638 (-4075 4625);
FORCEPROP 1 LAST TOLERANCE 1%
J 0
(-4050 4625);
DISPLAY 0.510638 (-4050 4625);
FORCEPROP 1 LAST MATERIAL CHIP
J 0
(-3975 4625);
DISPLAY 0.510638 (-3975 4625);
FORCEPROP 1 LAST $LOCATION R1930
J 0
(-4525 4625);
DISPLAY 0.787234 (-4525 4625);
FORCEPROP 1 LASTPIN (-4350 4625) $PN 1
J 0
(-4338 4637);
DISPLAY 0.787234 (-4338 4637);
PAINT MONO (-4338 4637);
FORCEPROP 1 LASTPIN (-4150 4625) $PN 2
J 0
(-4188 4637);
DISPLAY 0.787234 (-4188 4637);
PAINT MONO (-4188 4637);
FORCEPROP 2 LAST CDS_LIB pure_quanta
J 0
(-4250 4625);
DISPLAY INVISIBLE (-4250 4625);
FORCEPROP 1 LAST WATTAGE 1/16W
J 2
(-4050 4750);
DISPLAY 0.510638 (-4050 4750);
DISPLAY INVISIBLE (-4050 4750);
FORCEPROP 1 LAST PACK_TYPE 0402LF
J 0
(-4425 4750);
DISPLAY 0.510638 (-4425 4750);
DISPLAY INVISIBLE (-4425 4750);
FORCEPROP 1 LAST PATH I36
J 0
(-4300 4775);
DISPLAY 0.978723 (-4300 4775);
PAINT WHITE (-4300 4775);
DISPLAY INVISIBLE (-4300 4775);
FORCEPROP 0 LAST CDS_LOCATION R1930
J 0
(-4525 4675);
DISPLAY 1.021277 (-4525 4675);
DISPLAY INVISIBLE (-4525 4675);
FORCEPROP 0 LAST $SEC 1
J 0
(-4525 4675);
DISPLAY 0.680851 (-4525 4675);
PAINT MONO (-4525 4675);
DISPLAY INVISIBLE (-4525 4675);
FORCEPROP 0 LAST CDS_SEC 1
J 0
(-4525 4675);
DISPLAY 1.021277 (-4525 4675);
DISPLAY INVISIBLE (-4525 4675);
FORCEADD Q_RES..1
(-4250 4725);
FORCEPROP 1 LAST PART_NUMBER CS31002FB08
J 0
(-4425 4800);
DISPLAY 0.510638 (-4425 4800);
DISPLAY INVISIBLE (-4425 4800);
FORCEPROP 1 LAST PACK_TYPE 0402LF
J 0
(-4425 4850);
DISPLAY 0.510638 (-4425 4850);
FORCEPROP 1 LAST TOLERANCE 1%
J 0
(-4050 4725);
DISPLAY 0.510638 (-4050 4725);
FORCEPROP 1 LAST VALUE 10K
J 2
(-4075 4725);
DISPLAY 0.510638 (-4075 4725);
FORCEPROP 1 LAST MATERIAL CHIP
J 0
(-3975 4725);
DISPLAY 0.510638 (-3975 4725);
FORCEPROP 1 LAST WATTAGE 1/16W
J 2
(-4150 4850);
DISPLAY 0.510638 (-4150 4850);
FORCEPROP 1 LAST $LOCATION R1929
J 0
(-4525 4725);
DISPLAY 0.787234 (-4525 4725);
FORCEPROP 1 LASTPIN (-4350 4725) $PN 1
J 0
(-4338 4737);
DISPLAY 0.787234 (-4338 4737);
PAINT MONO (-4338 4737);
FORCEPROP 1 LASTPIN (-4150 4725) $PN 2
J 0
(-4188 4737);
DISPLAY 0.787234 (-4188 4737);
PAINT MONO (-4188 4737);
FORCEPROP 2 LAST CDS_LIB pure_quanta
J 0
(-4250 4725);
DISPLAY INVISIBLE (-4250 4725);
FORCEPROP 1 LAST PATH I37
J 0
(-4300 4875);
DISPLAY 0.978723 (-4300 4875);
PAINT WHITE (-4300 4875);
DISPLAY INVISIBLE (-4300 4875);
FORCEPROP 0 LAST CDS_LOCATION R1929
J 0
(-4050 4875);
DISPLAY 1.021277 (-4050 4875);
DISPLAY INVISIBLE (-4050 4875);
FORCEPROP 0 LAST $SEC 1
J 0
(-4050 4875);
DISPLAY 0.680851 (-4050 4875);
PAINT MONO (-4050 4875);
DISPLAY INVISIBLE (-4050 4875);
FORCEPROP 0 LAST CDS_SEC 1
J 0
(-4050 4875);
DISPLAY 1.021277 (-4050 4875);
DISPLAY INVISIBLE (-4050 4875);
FORCEADD OFFPAGE..1
(-3850 5750);
FORCEPROP 2 LAST $XR2 154 
J 0
(-4342 5750);
DISPLAY 0.638298 (-4342 5750);
PAINT MONO (-4342 5750);
FORCEPROP 2 LAST $XR1 158 
J 0
(-4222 5750);
DISPLAY 0.638298 (-4222 5750);
PAINT MONO (-4222 5750);
FORCEPROP 2 LAST $XR0 153 
J 0
(-4102 5750);
DISPLAY 0.638298 (-4102 5750);
PAINT MONO (-4102 5750);
FORCEPROP 2 LAST CDS_LIB standard
J 0
(-3850 5750);
PAINT MONO (-3850 5750);
DISPLAY INVISIBLE (-3850 5750);
FORCEPROP 1 LAST OFFPAGE TRUE
J 0
(-3525 5625);
DISPLAY 0.872340 (-3525 5625);
PAINT GREEN (-3525 5625);
DISPLAY INVISIBLE (-3525 5625);
FORCEPROP 1 LAST COMMENT_BODY TRUE
J 0
(-3725 5650);
DISPLAY 0.872340 (-3725 5650);
PAINT GREEN (-3725 5650);
DISPLAY INVISIBLE (-3725 5650);
FORCEPROP 2 LAST PATH I38
J 0
(-4125 5800);
DISPLAY 1.021277 (-4125 5800);
DISPLAY INVISIBLE (-4125 5800);
FORCEADD OFFPAGE..1
(-3850 5850);
FORCEPROP 2 LAST $XR0 155 
J 0
(-4102 5850);
DISPLAY 0.638298 (-4102 5850);
PAINT MONO (-4102 5850);
FORCEPROP 2 LAST CDS_LIB standard
J 0
(-3850 5850);
PAINT MONO (-3850 5850);
DISPLAY INVISIBLE (-3850 5850);
FORCEPROP 1 LAST OFFPAGE TRUE
J 0
(-3525 5725);
DISPLAY 0.872340 (-3525 5725);
PAINT GREEN (-3525 5725);
DISPLAY INVISIBLE (-3525 5725);
FORCEPROP 1 LAST COMMENT_BODY TRUE
J 0
(-3725 5750);
DISPLAY 0.872340 (-3725 5750);
PAINT GREEN (-3725 5750);
DISPLAY INVISIBLE (-3725 5750);
FORCEPROP 2 LAST PATH I39
J 0
(-4125 5900);
DISPLAY 1.021277 (-4125 5900);
DISPLAY INVISIBLE (-4125 5900);
FORCEADD Q_RES..2
(-3850 1725);
FORCEPROP 1 LAST PART_NUMBER CS24702FB06
J 0
(-3810 1600);
DISPLAY 0.787234 (-3810 1600);
DISPLAY INVISIBLE (-3810 1600);
FORCEPROP 1 LAST VALUE 4.7K
J 0
(-3805 1800);
DISPLAY 0.787234 (-3805 1800);
FORCEPROP 1 LAST WATTAGE 1/16W
J 0
(-3810 1700);
DISPLAY 0.787234 (-3810 1700);
FORCEPROP 1 LAST TOLERANCE 1%
J 0
(-3805 1750);
DISPLAY 0.787234 (-3805 1750);
FORCEPROP 1 LAST MATERIAL CHIP
J 0
(-3810 1650);
DISPLAY 0.787234 (-3810 1650);
FORCEPROP 1 LAST PACK_TYPE 0402LF
J 0
(-3810 1550);
DISPLAY 0.787234 (-3810 1550);
FORCEPROP 1 LAST $LOCATION R415
J 0
(-3805 1850);
DISPLAY 0.978723 (-3805 1850);
FORCEPROP 1 LASTPIN (-3850 1825) $PN 1
J 0
(-3845 1787);
DISPLAY 0.787234 (-3845 1787);
FORCEPROP 1 LASTPIN (-3850 1625) $PN 2
J 0
(-3845 1635);
DISPLAY 0.787234 (-3845 1635);
FORCEPROP 2 LAST CDS_LIB pure_quanta
J 0
(-3850 1725);
PAINT MONO (-3850 1725);
DISPLAY INVISIBLE (-3850 1725);
FORCEPROP 1 LAST PATH I4
J 0
(-3800 1900);
DISPLAY 0.978723 (-3800 1900);
PAINT WHITE (-3800 1900);
DISPLAY INVISIBLE (-3800 1900);
FORCEPROP 2 LAST CDS_LOCATION R415
J 0
(-3800 1950);
DISPLAY 1.021277 (-3800 1950);
DISPLAY INVISIBLE (-3800 1950);
FORCEPROP 2 LAST $SEC 1
J 0
(-3800 1950);
DISPLAY 0.680851 (-3800 1950);
PAINT MONO (-3800 1950);
DISPLAY INVISIBLE (-3800 1950);
FORCEPROP 2 LAST CDS_SEC 1
J 0
(-3800 1950);
DISPLAY 1.021277 (-3800 1950);
DISPLAY INVISIBLE (-3800 1950);
FORCEADD OFFPAGE..1
(-3850 5950);
FORCEPROP 2 LAST $XR0 154 
J 0
(-4102 5950);
DISPLAY 0.638298 (-4102 5950);
PAINT MONO (-4102 5950);
FORCEPROP 2 LAST CDS_LIB standard
J 0
(-3850 5950);
PAINT MONO (-3850 5950);
DISPLAY INVISIBLE (-3850 5950);
FORCEPROP 1 LAST OFFPAGE TRUE
J 0
(-3525 5825);
DISPLAY 0.872340 (-3525 5825);
PAINT GREEN (-3525 5825);
DISPLAY INVISIBLE (-3525 5825);
FORCEPROP 1 LAST COMMENT_BODY TRUE
J 0
(-3725 5850);
DISPLAY 0.872340 (-3725 5850);
PAINT GREEN (-3725 5850);
DISPLAY INVISIBLE (-3725 5850);
FORCEPROP 2 LAST PATH I40
J 0
(-4125 6000);
DISPLAY 1.021277 (-4125 6000);
DISPLAY INVISIBLE (-4125 6000);
FORCEADD OFFPAGE..1
(-3850 5900);
FORCEPROP 2 LAST $XR0 154 
J 0
(-4102 5900);
DISPLAY 0.638298 (-4102 5900);
PAINT MONO (-4102 5900);
FORCEPROP 2 LAST CDS_LIB standard
J 0
(-3850 5900);
PAINT MONO (-3850 5900);
DISPLAY INVISIBLE (-3850 5900);
FORCEPROP 1 LAST OFFPAGE TRUE
J 0
(-3525 5775);
DISPLAY 0.872340 (-3525 5775);
PAINT GREEN (-3525 5775);
DISPLAY INVISIBLE (-3525 5775);
FORCEPROP 1 LAST COMMENT_BODY TRUE
J 0
(-3725 5800);
DISPLAY 0.872340 (-3725 5800);
PAINT GREEN (-3725 5800);
DISPLAY INVISIBLE (-3725 5800);
FORCEPROP 2 LAST PATH I41
J 0
(-4125 5950);
DISPLAY 1.021277 (-4125 5950);
DISPLAY INVISIBLE (-4125 5950);
FORCEADD OFFPAGE..1
(-3850 6000);
FORCEPROP 2 LAST $XR0 154 
J 0
(-4102 6000);
DISPLAY 0.638298 (-4102 6000);
PAINT MONO (-4102 6000);
FORCEPROP 2 LAST CDS_LIB standard
J 0
(-3850 6000);
PAINT MONO (-3850 6000);
DISPLAY INVISIBLE (-3850 6000);
FORCEPROP 1 LAST OFFPAGE TRUE
J 0
(-3525 5875);
DISPLAY 0.872340 (-3525 5875);
PAINT GREEN (-3525 5875);
DISPLAY INVISIBLE (-3525 5875);
FORCEPROP 1 LAST COMMENT_BODY TRUE
J 0
(-3725 5900);
DISPLAY 0.872340 (-3725 5900);
PAINT GREEN (-3725 5900);
DISPLAY INVISIBLE (-3725 5900);
FORCEPROP 2 LAST PATH I42
J 0
(-4125 6050);
DISPLAY 1.021277 (-4125 6050);
DISPLAY INVISIBLE (-4125 6050);
FORCEADD OFFPAGE..5
(-2800 4150);
FORCEPROP 2 LAST $XR1 165 
J 0
(-3205 4150);
DISPLAY 0.638298 (-3205 4150);
PAINT MONO (-3205 4150);
FORCEPROP 2 LAST $XR0 156 
J 0
(-3085 4150);
DISPLAY 0.638298 (-3085 4150);
PAINT MONO (-3085 4150);
FORCEPROP 2 LAST CDS_LIB standard
J 0
(-2800 4150);
PAINT MONO (-2800 4150);
DISPLAY INVISIBLE (-2800 4150);
FORCEPROP 1 LAST OFFPAGE TRUE
J 0
(-2475 4025);
DISPLAY 0.872340 (-2475 4025);
PAINT GREEN (-2475 4025);
DISPLAY INVISIBLE (-2475 4025);
FORCEPROP 1 LAST COMMENT_BODY TRUE
J 0
(-2700 4075);
DISPLAY 0.872340 (-2700 4075);
PAINT GREEN (-2700 4075);
DISPLAY INVISIBLE (-2700 4075);
FORCEPROP 2 LAST PATH I43
J 0
(-3100 4200);
DISPLAY 1.021277 (-3100 4200);
DISPLAY INVISIBLE (-3100 4200);
FORCEADD OFFPAGE..2
(-2900 4425);
FORCEPROP 2 LAST $XR2 213 
J 0
(-2471 4425);
DISPLAY 0.638298 (-2471 4425);
PAINT MONO (-2471 4425);
FORCEPROP 2 LAST $XR1 154 
J 0
(-2591 4425);
DISPLAY 0.638298 (-2591 4425);
PAINT MONO (-2591 4425);
FORCEPROP 2 LAST $XR0 153 
J 0
(-2711 4425);
DISPLAY 0.638298 (-2711 4425);
PAINT MONO (-2711 4425);
FORCEPROP 2 LAST CDS_LIB standard
J 0
(-2900 4425);
DISPLAY INVISIBLE (-2900 4425);
FORCEPROP 1 LAST OFFPAGE TRUE
J 0
(-2575 4300);
DISPLAY 0.872340 (-2575 4300);
PAINT GREEN (-2575 4300);
DISPLAY INVISIBLE (-2575 4300);
FORCEPROP 1 LAST COMMENT_BODY TRUE
J 0
(-2945 4330);
DISPLAY 0.872340 (-2945 4330);
PAINT GREEN (-2945 4330);
DISPLAY INVISIBLE (-2945 4330);
FORCEPROP 2 LAST PATH I44
J 0
(-2400 4475);
DISPLAY 1.021277 (-2400 4475);
DISPLAY INVISIBLE (-2400 4475);
FORCEADD OFFPAGE..2
(-2900 4625);
FORCEPROP 2 LAST $XR1 214 
J 0
(-2591 4625);
DISPLAY 0.638298 (-2591 4625);
PAINT MONO (-2591 4625);
FORCEPROP 2 LAST $XR0 153 
J 0
(-2711 4625);
DISPLAY 0.638298 (-2711 4625);
PAINT MONO (-2711 4625);
FORCEPROP 2 LAST CDS_LIB standard
J 0
(-2900 4625);
DISPLAY INVISIBLE (-2900 4625);
FORCEPROP 1 LAST OFFPAGE TRUE
J 0
(-2575 4500);
DISPLAY 0.872340 (-2575 4500);
PAINT GREEN (-2575 4500);
DISPLAY INVISIBLE (-2575 4500);
FORCEPROP 1 LAST COMMENT_BODY TRUE
J 0
(-2945 4530);
DISPLAY 0.872340 (-2945 4530);
PAINT GREEN (-2945 4530);
DISPLAY INVISIBLE (-2945 4530);
FORCEPROP 2 LAST PATH I45
J 0
(-2700 4675);
DISPLAY 1.021277 (-2700 4675);
DISPLAY INVISIBLE (-2700 4675);
FORCEADD OFFPAGE..2
(-2900 4725);
FORCEPROP 2 LAST $XR2 154 
J 0
(-2471 4725);
DISPLAY 0.638298 (-2471 4725);
PAINT MONO (-2471 4725);
FORCEPROP 2 LAST $XR1 153 
J 0
(-2591 4725);
DISPLAY 0.638298 (-2591 4725);
PAINT MONO (-2591 4725);
FORCEPROP 2 LAST $XR0 158 
J 0
(-2711 4725);
DISPLAY 0.638298 (-2711 4725);
PAINT MONO (-2711 4725);
FORCEPROP 2 LAST CDS_LIB standard
J 0
(-2900 4725);
DISPLAY INVISIBLE (-2900 4725);
FORCEPROP 1 LAST OFFPAGE TRUE
J 0
(-2575 4600);
DISPLAY 0.872340 (-2575 4600);
PAINT GREEN (-2575 4600);
DISPLAY INVISIBLE (-2575 4600);
FORCEPROP 1 LAST COMMENT_BODY TRUE
J 0
(-2945 4630);
DISPLAY 0.872340 (-2945 4630);
PAINT GREEN (-2945 4630);
DISPLAY INVISIBLE (-2945 4630);
FORCEPROP 2 LAST PATH I46
J 0
(-2400 4775);
DISPLAY 1.021277 (-2400 4775);
DISPLAY INVISIBLE (-2400 4775);
FORCEADD OFFPAGE..1
(-2800 5525);
FORCEPROP 2 LAST $XR0 174 
J 0
(-3052 5525);
DISPLAY 0.638298 (-3052 5525);
PAINT MONO (-3052 5525);
FORCEPROP 2 LAST CDS_LIB standard
J 0
(-2800 5525);
DISPLAY INVISIBLE (-2800 5525);
FORCEPROP 1 LAST OFFPAGE TRUE
J 0
(-2475 5400);
DISPLAY 0.872340 (-2475 5400);
PAINT GREEN (-2475 5400);
DISPLAY INVISIBLE (-2475 5400);
FORCEPROP 1 LAST COMMENT_BODY TRUE
J 0
(-2675 5425);
DISPLAY 0.872340 (-2675 5425);
PAINT GREEN (-2675 5425);
DISPLAY INVISIBLE (-2675 5425);
FORCEPROP 2 LAST PATH I47
J 0
(-3075 5575);
DISPLAY 1.021277 (-3075 5575);
DISPLAY INVISIBLE (-3075 5575);
FORCEADD OFFPAGE..1
(-2800 5600);
FORCEPROP 2 LAST $XR0 209 
J 0
(-3052 5600);
DISPLAY 0.638298 (-3052 5600);
PAINT MONO (-3052 5600);
FORCEPROP 2 LAST CDS_LIB standard
J 0
(-2800 5600);
PAINT MONO (-2800 5600);
DISPLAY INVISIBLE (-2800 5600);
FORCEPROP 1 LAST OFFPAGE TRUE
J 0
(-2475 5475);
DISPLAY 0.872340 (-2475 5475);
PAINT GREEN (-2475 5475);
DISPLAY INVISIBLE (-2475 5475);
FORCEPROP 1 LAST COMMENT_BODY TRUE
J 0
(-2675 5500);
DISPLAY 0.872340 (-2675 5500);
PAINT GREEN (-2675 5500);
DISPLAY INVISIBLE (-2675 5500);
FORCEPROP 2 LAST PATH I48
J 0
(-3075 5650);
DISPLAY 1.021277 (-3075 5650);
DISPLAY INVISIBLE (-3075 5650);
FORCEADD Q_RES..2
(-4325 2250);
FORCEPROP 1 LAST PART_NUMBER CS24702FB06
J 0
(-4285 2125);
DISPLAY 0.787234 (-4285 2125);
DISPLAY INVISIBLE (-4285 2125);
FORCEPROP 1 LAST TOLERANCE 1%
J 0
(-4280 2275);
DISPLAY 0.787234 (-4280 2275);
FORCEPROP 1 LAST VALUE 4.7K
J 0
(-4280 2325);
DISPLAY 0.787234 (-4280 2325);
FORCEPROP 1 LAST MATERIAL EMPTY
J 0
(-4285 2175);
DISPLAY 0.787234 (-4285 2175);
FORCEPROP 1 LAST PACK_TYPE 0402LF
J 0
(-4285 2075);
DISPLAY 0.787234 (-4285 2075);
FORCEPROP 1 LAST WATTAGE 1/16W
J 0
(-4285 2225);
DISPLAY 0.787234 (-4285 2225);
FORCEPROP 1 LAST $LOCATION R409
J 0
(-4280 2375);
DISPLAY 0.978723 (-4280 2375);
FORCEPROP 1 LASTPIN (-4325 2350) $PN 1
J 0
(-4320 2312);
DISPLAY 0.787234 (-4320 2312);
FORCEPROP 1 LASTPIN (-4325 2150) $PN 2
J 0
(-4320 2160);
DISPLAY 0.787234 (-4320 2160);
FORCEPROP 2 LAST CDS_LIB pure_quanta
J 0
(-4325 2250);
PAINT MONO (-4325 2250);
DISPLAY INVISIBLE (-4325 2250);
FORCEPROP 1 LAST PATH I5
J 0
(-4275 2425);
DISPLAY 0.978723 (-4275 2425);
PAINT WHITE (-4275 2425);
DISPLAY INVISIBLE (-4275 2425);
FORCEPROP 2 LAST CDS_LOCATION R409
J 0
(-4275 2475);
DISPLAY 1.021277 (-4275 2475);
DISPLAY INVISIBLE (-4275 2475);
FORCEPROP 2 LAST $SEC 1
J 0
(-4275 2475);
DISPLAY 0.680851 (-4275 2475);
PAINT MONO (-4275 2475);
DISPLAY INVISIBLE (-4275 2475);
FORCEPROP 2 LAST CDS_SEC 1
J 0
(-4275 2475);
DISPLAY 1.021277 (-4275 2475);
DISPLAY INVISIBLE (-4275 2475);
FORCEADD OFFPAGE..1
(-2800 5650);
FORCEPROP 2 LAST $XR0 209 
J 0
(-3052 5650);
DISPLAY 0.638298 (-3052 5650);
PAINT MONO (-3052 5650);
FORCEPROP 2 LAST CDS_LIB standard
J 0
(-2800 5650);
PAINT MONO (-2800 5650);
DISPLAY INVISIBLE (-2800 5650);
FORCEPROP 1 LAST OFFPAGE TRUE
J 0
(-2475 5525);
DISPLAY 0.872340 (-2475 5525);
PAINT GREEN (-2475 5525);
DISPLAY INVISIBLE (-2475 5525);
FORCEPROP 1 LAST COMMENT_BODY TRUE
J 0
(-2675 5550);
DISPLAY 0.872340 (-2675 5550);
PAINT GREEN (-2675 5550);
DISPLAY INVISIBLE (-2675 5550);
FORCEPROP 2 LAST PATH I50
J 0
(-3075 5700);
DISPLAY 1.021277 (-3075 5700);
DISPLAY INVISIBLE (-3075 5700);
FORCEADD Q_RES..1
(-2900 5750);
FORCEPROP 1 LAST PART_NUMBER CS00002JB13
J 0
(-3025 5825);
DISPLAY 0.638298 (-3025 5825);
DISPLAY INVISIBLE (-3025 5825);
FORCEPROP 1 LAST PACK_TYPE 0402LF
J 0
(-2625 5750);
DISPLAY 0.638298 (-2625 5750);
FORCEPROP 1 LAST VALUE 0
J 2
(-2725 5750);
DISPLAY 0.638298 (-2725 5750);
FORCEPROP 1 LAST TOLERANCE 5%
J 0
(-2700 5750);
DISPLAY 0.638298 (-2700 5750);
FORCEPROP 1 LAST $LOCATION R1671
J 0
(-3150 5750);
DISPLAY 0.787234 (-3150 5750);
FORCEPROP 1 LASTPIN (-3000 5750) $PN 1
J 0
(-2988 5762);
DISPLAY 0.787234 (-2988 5762);
FORCEPROP 1 LASTPIN (-2800 5750) $PN 2
J 0
(-2838 5762);
DISPLAY 0.787234 (-2838 5762);
FORCEPROP 1 LAST WATTAGE 1/16W
J 2
(-2725 5875);
DISPLAY 0.638298 (-2725 5875);
DISPLAY INVISIBLE (-2725 5875);
FORCEPROP 1 LAST MATERIAL CHIP
J 0
(-3025 5875);
DISPLAY 0.638298 (-3025 5875);
DISPLAY INVISIBLE (-3025 5875);
FORCEPROP 2 LAST CDS_LIB pure_quanta
J 0
(-2900 5750);
PAINT MONO (-2900 5750);
DISPLAY INVISIBLE (-2900 5750);
FORCEPROP 1 LAST PATH I51
J 0
(-2950 5900);
DISPLAY 0.978723 (-2950 5900);
PAINT WHITE (-2950 5900);
DISPLAY INVISIBLE (-2950 5900);
FORCEPROP 2 LAST CDS_LOCATION R1671
J 0
(-2950 5950);
DISPLAY 1.021277 (-2950 5950);
DISPLAY INVISIBLE (-2950 5950);
FORCEPROP 2 LAST $SEC 1
J 0
(-2950 5950);
DISPLAY 0.680851 (-2950 5950);
PAINT MONO (-2950 5950);
DISPLAY INVISIBLE (-2950 5950);
FORCEPROP 2 LAST CDS_SEC 1
J 0
(-2950 5950);
DISPLAY 1.021277 (-2950 5950);
DISPLAY INVISIBLE (-2950 5950);
FORCEADD Q_RES..1
(-2900 5900);
FORCEPROP 1 LAST PART_NUMBER CS00002JB13
J 0
(-3025 5975);
DISPLAY 0.638298 (-3025 5975);
DISPLAY INVISIBLE (-3025 5975);
FORCEPROP 1 LAST TOLERANCE 5%
J 0
(-2700 5900);
DISPLAY 0.638298 (-2700 5900);
FORCEPROP 1 LAST PACK_TYPE 0402LF
J 0
(-2625 5900);
DISPLAY 0.638298 (-2625 5900);
FORCEPROP 1 LAST VALUE 0
J 2
(-2725 5900);
DISPLAY 0.638298 (-2725 5900);
FORCEPROP 1 LAST $LOCATION R418
J 0
(-3125 5900);
DISPLAY 0.787234 (-3125 5900);
FORCEPROP 1 LASTPIN (-3000 5900) $PN 1
J 0
(-2988 5912);
DISPLAY 0.787234 (-2988 5912);
FORCEPROP 1 LASTPIN (-2800 5900) $PN 2
J 0
(-2838 5912);
DISPLAY 0.787234 (-2838 5912);
FORCEPROP 2 LAST CDS_LIB pure_quanta
J 0
(-2900 5900);
PAINT MONO (-2900 5900);
DISPLAY INVISIBLE (-2900 5900);
FORCEPROP 1 LAST MATERIAL CHIP
J 0
(-3025 6025);
DISPLAY 0.638298 (-3025 6025);
DISPLAY INVISIBLE (-3025 6025);
FORCEPROP 1 LAST WATTAGE 1/16W
J 2
(-2725 6025);
DISPLAY 0.638298 (-2725 6025);
DISPLAY INVISIBLE (-2725 6025);
FORCEPROP 1 LAST PATH I52
J 0
(-2950 6050);
DISPLAY 0.978723 (-2950 6050);
PAINT WHITE (-2950 6050);
DISPLAY INVISIBLE (-2950 6050);
FORCEPROP 2 LAST CDS_LOCATION R418
J 0
(-2950 6100);
DISPLAY 1.021277 (-2950 6100);
DISPLAY INVISIBLE (-2950 6100);
FORCEPROP 2 LAST $SEC 1
J 0
(-2950 6100);
DISPLAY 0.680851 (-2950 6100);
PAINT MONO (-2950 6100);
DISPLAY INVISIBLE (-2950 6100);
FORCEPROP 2 LAST CDS_SEC 1
J 0
(-2950 6100);
DISPLAY 1.021277 (-2950 6100);
DISPLAY INVISIBLE (-2950 6100);
FORCEADD Q_RES..1
(-2900 5950);
FORCEPROP 1 LAST PART_NUMBER CS00002JB13
J 0
(-3025 6025);
DISPLAY 0.638298 (-3025 6025);
DISPLAY INVISIBLE (-3025 6025);
FORCEPROP 1 LAST VALUE 0
J 2
(-2725 5950);
DISPLAY 0.638298 (-2725 5950);
FORCEPROP 1 LAST TOLERANCE 5%
J 0
(-2700 5950);
DISPLAY 0.638298 (-2700 5950);
FORCEPROP 1 LAST PACK_TYPE 0402LF
J 0
(-2625 5950);
DISPLAY 0.638298 (-2625 5950);
FORCEPROP 1 LAST $LOCATION R417
J 0
(-3125 5950);
DISPLAY 0.787234 (-3125 5950);
FORCEPROP 1 LASTPIN (-3000 5950) $PN 1
J 0
(-2988 5962);
DISPLAY 0.787234 (-2988 5962);
FORCEPROP 1 LASTPIN (-2800 5950) $PN 2
J 0
(-2838 5962);
DISPLAY 0.787234 (-2838 5962);
FORCEPROP 1 LAST WATTAGE 1/16W
J 2
(-2725 6075);
DISPLAY 0.638298 (-2725 6075);
DISPLAY INVISIBLE (-2725 6075);
FORCEPROP 1 LAST MATERIAL CHIP
J 0
(-3025 6075);
DISPLAY 0.638298 (-3025 6075);
DISPLAY INVISIBLE (-3025 6075);
FORCEPROP 2 LAST CDS_LIB pure_quanta
J 0
(-2900 5950);
PAINT MONO (-2900 5950);
DISPLAY INVISIBLE (-2900 5950);
FORCEPROP 1 LAST PATH I53
J 0
(-2950 6100);
DISPLAY 0.978723 (-2950 6100);
PAINT WHITE (-2950 6100);
DISPLAY INVISIBLE (-2950 6100);
FORCEPROP 2 LAST CDS_LOCATION R417
J 0
(-2950 6150);
DISPLAY 1.021277 (-2950 6150);
DISPLAY INVISIBLE (-2950 6150);
FORCEPROP 2 LAST $SEC 1
J 0
(-2950 6150);
DISPLAY 0.680851 (-2950 6150);
PAINT MONO (-2950 6150);
DISPLAY INVISIBLE (-2950 6150);
FORCEPROP 2 LAST CDS_SEC 1
J 0
(-2950 6150);
DISPLAY 1.021277 (-2950 6150);
DISPLAY INVISIBLE (-2950 6150);
FORCEADD Q_RES..1
(-2900 6000);
FORCEPROP 1 LAST PART_NUMBER CS00002JB13
J 0
(-3025 6075);
DISPLAY 0.638298 (-3025 6075);
DISPLAY INVISIBLE (-3025 6075);
FORCEPROP 1 LAST MATERIAL CHIP
J 0
(-3025 6125);
DISPLAY 0.638298 (-3025 6125);
FORCEPROP 1 LAST WATTAGE 1/16W
J 2
(-2725 6125);
DISPLAY 0.638298 (-2725 6125);
FORCEPROP 1 LAST TOLERANCE 5%
J 0
(-2700 6000);
DISPLAY 0.638298 (-2700 6000);
FORCEPROP 1 LAST VALUE 0
J 2
(-2725 6000);
DISPLAY 0.638298 (-2725 6000);
FORCEPROP 1 LAST PACK_TYPE 0402LF
J 0
(-2625 6000);
DISPLAY 0.638298 (-2625 6000);
FORCEPROP 1 LAST $LOCATION R416
J 0
(-3125 6000);
DISPLAY 0.787234 (-3125 6000);
FORCEPROP 1 LASTPIN (-3000 6000) $PN 1
J 0
(-2988 6012);
DISPLAY 0.787234 (-2988 6012);
FORCEPROP 1 LASTPIN (-2800 6000) $PN 2
J 0
(-2838 6012);
DISPLAY 0.787234 (-2838 6012);
FORCEPROP 2 LAST CDS_LIB pure_quanta
J 0
(-2900 6000);
PAINT MONO (-2900 6000);
DISPLAY INVISIBLE (-2900 6000);
FORCEPROP 1 LAST PATH I54
J 0
(-2950 6150);
DISPLAY 0.978723 (-2950 6150);
PAINT WHITE (-2950 6150);
DISPLAY INVISIBLE (-2950 6150);
FORCEPROP 2 LAST CDS_LOCATION R416
J 0
(-2950 6200);
DISPLAY 1.021277 (-2950 6200);
DISPLAY INVISIBLE (-2950 6200);
FORCEPROP 2 LAST $SEC 1
J 0
(-2950 6200);
DISPLAY 0.680851 (-2950 6200);
PAINT MONO (-2950 6200);
DISPLAY INVISIBLE (-2950 6200);
FORCEPROP 2 LAST CDS_SEC 1
J 0
(-2950 6200);
DISPLAY 1.021277 (-2950 6200);
DISPLAY INVISIBLE (-2950 6200);
FORCEADD OFFPAGE..5
(-4075 7100);
FORCEPROP 2 LAST $XR2 213 
J 0
(-4570 7100);
DISPLAY 0.638298 (-4570 7100);
PAINT MONO (-4570 7100);
FORCEPROP 2 LAST $XR1 154 
J 0
(-4450 7100);
DISPLAY 0.638298 (-4450 7100);
PAINT MONO (-4450 7100);
FORCEPROP 2 LAST $XR0 153 
J 0
(-4330 7100);
DISPLAY 0.638298 (-4330 7100);
PAINT MONO (-4330 7100);
FORCEPROP 2 LAST CDS_LIB standard
J 0
(-4075 7100);
DISPLAY INVISIBLE (-4075 7100);
FORCEPROP 1 LAST OFFPAGE TRUE
J 0
(-3750 6975);
DISPLAY 0.872340 (-3750 6975);
PAINT GREEN (-3750 6975);
DISPLAY INVISIBLE (-3750 6975);
FORCEPROP 1 LAST COMMENT_BODY TRUE
J 0
(-3975 7025);
DISPLAY 0.872340 (-3975 7025);
PAINT GREEN (-3975 7025);
DISPLAY INVISIBLE (-3975 7025);
FORCEPROP 2 LAST PATH I55
J 0
(-4350 7150);
DISPLAY 1.021277 (-4350 7150);
DISPLAY INVISIBLE (-4350 7150);
FORCEADD Q_RES..1
(-2900 7050);
FORCEPROP 1 LAST PART_NUMBER CS00002JB13
J 0
(-3025 7125);
DISPLAY 0.638298 (-3025 7125);
DISPLAY INVISIBLE (-3025 7125);
FORCEPROP 1 LAST PACK_TYPE 0402LF
J 0
(-2625 7050);
DISPLAY 0.638298 (-2625 7050);
FORCEPROP 1 LAST VALUE 0
J 2
(-2725 7050);
DISPLAY 0.638298 (-2725 7050);
FORCEPROP 1 LAST TOLERANCE 5%
J 0
(-2700 7050);
DISPLAY 0.638298 (-2700 7050);
FORCEPROP 1 LAST $LOCATION R429
J 0
(-3125 7050);
DISPLAY 0.638298 (-3125 7050);
FORCEPROP 1 LASTPIN (-3000 7050) $PN 1
J 0
(-2988 7062);
DISPLAY 0.787234 (-2988 7062);
FORCEPROP 1 LASTPIN (-2800 7050) $PN 2
J 0
(-2838 7062);
DISPLAY 0.787234 (-2838 7062);
FORCEPROP 1 LAST MATERIAL CHIP
J 0
(-3025 7175);
DISPLAY 0.638298 (-3025 7175);
DISPLAY INVISIBLE (-3025 7175);
FORCEPROP 1 LAST WATTAGE 1/16W
J 2
(-2725 7175);
DISPLAY 0.638298 (-2725 7175);
DISPLAY INVISIBLE (-2725 7175);
FORCEPROP 2 LAST CDS_LIB pure_quanta
J 0
(-2900 7050);
PAINT MONO (-2900 7050);
DISPLAY INVISIBLE (-2900 7050);
FORCEPROP 1 LAST PATH I58
J 0
(-2950 7200);
DISPLAY 0.978723 (-2950 7200);
PAINT WHITE (-2950 7200);
DISPLAY INVISIBLE (-2950 7200);
FORCEPROP 2 LAST CDS_LOCATION R429
J 0
(-2950 7250);
DISPLAY 1.021277 (-2950 7250);
DISPLAY INVISIBLE (-2950 7250);
FORCEPROP 2 LAST $SEC 1
J 0
(-2950 7250);
DISPLAY 0.680851 (-2950 7250);
PAINT MONO (-2950 7250);
DISPLAY INVISIBLE (-2950 7250);
FORCEPROP 2 LAST CDS_SEC 1
J 0
(-2950 7250);
DISPLAY 1.021277 (-2950 7250);
DISPLAY INVISIBLE (-2950 7250);
FORCEADD TAP..1
R 2
(-1750 3950);
FORCEPROP 3 LASTPIN (-1700 3950) SIG_NAME P5E_CPU0_PE1_TX_C_DP<8>
J 0
(-1690 3960);
DISPLAY 0.659574 (-1690 3960);
PAINT MONO (-1690 3960);
DISPLAY INVISIBLE (-1690 3960);
FORCEPROP 1 LASTPIN (-1700 3950) BN 8
J 2
(-1688 3958);
DISPLAY 0.680851 (-1688 3958);
PAINT GREEN (-1688 3958);
FORCEPROP 2 LAST CDS_LIB standard
J 0
(-1750 3950);
PAINT MONO (-1750 3950);
DISPLAY INVISIBLE (-1750 3950);
FORCEPROP 1 LAST BODY_TYPE PLUMBING
J 2
(-1750 4000);
DISPLAY 0.872340 (-1750 4000);
PAINT GREEN (-1750 4000);
DISPLAY INVISIBLE (-1750 4000);
FORCEPROP 1 LAST HDL_TAP TRUE
J 2
(-2075 3825);
DISPLAY 0.872340 (-2075 3825);
PAINT GREEN (-2075 3825);
DISPLAY INVISIBLE (-2075 3825);
FORCEPROP 1 LAST PATH I59
J 2
(-1748 3950);
DISPLAY 0.872340 (-1748 3950);
PAINT GREEN (-1748 3950);
DISPLAY INVISIBLE (-1748 3950);
FORCEADD Q_RES..2
(-3850 2250);
FORCEPROP 1 LAST PART_NUMBER CS24702FB06
J 0
(-3810 2125);
DISPLAY 0.787234 (-3810 2125);
DISPLAY INVISIBLE (-3810 2125);
FORCEPROP 1 LAST WATTAGE 1/16W
J 0
(-3810 2225);
DISPLAY 0.787234 (-3810 2225);
FORCEPROP 1 LAST MATERIAL EMPTY
J 0
(-3810 2175);
DISPLAY 0.787234 (-3810 2175);
FORCEPROP 1 LAST TOLERANCE 1%
J 0
(-3805 2275);
DISPLAY 0.787234 (-3805 2275);
FORCEPROP 1 LAST VALUE 4.7K
J 0
(-3805 2325);
DISPLAY 0.787234 (-3805 2325);
FORCEPROP 1 LAST PACK_TYPE 0402LF
J 0
(-3810 2075);
DISPLAY 0.787234 (-3810 2075);
FORCEPROP 1 LAST $LOCATION R414
J 0
(-3805 2375);
DISPLAY 0.978723 (-3805 2375);
FORCEPROP 1 LASTPIN (-3850 2350) $PN 1
J 0
(-3845 2312);
DISPLAY 0.787234 (-3845 2312);
FORCEPROP 1 LASTPIN (-3850 2150) $PN 2
J 0
(-3845 2160);
DISPLAY 0.787234 (-3845 2160);
FORCEPROP 2 LAST CDS_LIB pure_quanta
J 0
(-3850 2250);
PAINT MONO (-3850 2250);
DISPLAY INVISIBLE (-3850 2250);
FORCEPROP 1 LAST PATH I6
J 0
(-3800 2425);
DISPLAY 0.978723 (-3800 2425);
PAINT WHITE (-3800 2425);
DISPLAY INVISIBLE (-3800 2425);
FORCEPROP 2 LAST CDS_LOCATION R414
J 0
(-3800 2475);
DISPLAY 1.021277 (-3800 2475);
DISPLAY INVISIBLE (-3800 2475);
FORCEPROP 2 LAST $SEC 1
J 0
(-3800 2475);
DISPLAY 0.680851 (-3800 2475);
PAINT MONO (-3800 2475);
DISPLAY INVISIBLE (-3800 2475);
FORCEPROP 2 LAST CDS_SEC 1
J 0
(-3800 2475);
DISPLAY 1.021277 (-3800 2475);
DISPLAY INVISIBLE (-3800 2475);
FORCEADD TAP..1
R 2
(-1750 4450);
FORCEPROP 3 LASTPIN (-1700 4450) SIG_NAME P5E_CPU0_PE1_TX_C_DP<6>
J 0
(-1690 4460);
DISPLAY 0.659574 (-1690 4460);
PAINT MONO (-1690 4460);
DISPLAY INVISIBLE (-1690 4460);
FORCEPROP 1 LASTPIN (-1700 4450) BN 6
J 2
(-1688 4458);
DISPLAY 0.680851 (-1688 4458);
PAINT GREEN (-1688 4458);
FORCEPROP 2 LAST CDS_LIB standard
J 0
(-1750 4450);
PAINT MONO (-1750 4450);
DISPLAY INVISIBLE (-1750 4450);
FORCEPROP 1 LAST BODY_TYPE PLUMBING
J 2
(-1750 4500);
DISPLAY 0.872340 (-1750 4500);
PAINT GREEN (-1750 4500);
DISPLAY INVISIBLE (-1750 4500);
FORCEPROP 1 LAST HDL_TAP TRUE
J 2
(-2075 4325);
DISPLAY 0.872340 (-2075 4325);
PAINT GREEN (-2075 4325);
DISPLAY INVISIBLE (-2075 4325);
FORCEPROP 1 LAST PATH I62
J 2
(-1748 4450);
DISPLAY 0.872340 (-1748 4450);
PAINT GREEN (-1748 4450);
DISPLAY INVISIBLE (-1748 4450);
FORCEADD TAP..1
R 2
(-1750 4750);
FORCEPROP 3 LASTPIN (-1700 4750) SIG_NAME P5E_CPU0_PE1_TX_C_DP<4>
J 0
(-1690 4760);
DISPLAY 0.659574 (-1690 4760);
PAINT MONO (-1690 4760);
DISPLAY INVISIBLE (-1690 4760);
FORCEPROP 1 LASTPIN (-1700 4750) BN 4
J 2
(-1688 4758);
DISPLAY 0.680851 (-1688 4758);
PAINT GREEN (-1688 4758);
FORCEPROP 2 LAST CDS_LIB standard
J 0
(-1750 4750);
PAINT MONO (-1750 4750);
DISPLAY INVISIBLE (-1750 4750);
FORCEPROP 1 LAST BODY_TYPE PLUMBING
J 2
(-1750 4800);
DISPLAY 0.872340 (-1750 4800);
PAINT GREEN (-1750 4800);
DISPLAY INVISIBLE (-1750 4800);
FORCEPROP 1 LAST HDL_TAP TRUE
J 2
(-2075 4625);
DISPLAY 0.872340 (-2075 4625);
PAINT GREEN (-2075 4625);
DISPLAY INVISIBLE (-2075 4625);
FORCEPROP 1 LAST PATH I63
J 2
(-1748 4750);
DISPLAY 0.872340 (-1748 4750);
PAINT GREEN (-1748 4750);
DISPLAY INVISIBLE (-1748 4750);
FORCEADD TAP..1
R 2
(-1750 5200);
FORCEPROP 3 LASTPIN (-1700 5200) SIG_NAME P5E_CPU0_PE1_TX_C_DP<2>
J 0
(-1690 5210);
DISPLAY 0.659574 (-1690 5210);
PAINT MONO (-1690 5210);
DISPLAY INVISIBLE (-1690 5210);
FORCEPROP 1 LASTPIN (-1700 5200) BN 2
J 2
(-1688 5208);
DISPLAY 0.680851 (-1688 5208);
PAINT GREEN (-1688 5208);
FORCEPROP 2 LAST CDS_LIB standard
J 0
(-1750 5200);
PAINT MONO (-1750 5200);
DISPLAY INVISIBLE (-1750 5200);
FORCEPROP 1 LAST BODY_TYPE PLUMBING
J 2
(-1750 5250);
DISPLAY 0.872340 (-1750 5250);
PAINT GREEN (-1750 5250);
DISPLAY INVISIBLE (-1750 5250);
FORCEPROP 1 LAST HDL_TAP TRUE
J 2
(-2075 5075);
DISPLAY 0.872340 (-2075 5075);
PAINT GREEN (-2075 5075);
DISPLAY INVISIBLE (-2075 5075);
FORCEPROP 1 LAST PATH I66
J 2
(-1748 5200);
DISPLAY 0.872340 (-1748 5200);
PAINT GREEN (-1748 5200);
DISPLAY INVISIBLE (-1748 5200);
FORCEADD TAP..1
R 2
(-1600 4400);
FORCEPROP 3 LASTPIN (-1550 4400) SIG_NAME P5E_CPU0_PE1_TX_C_DN<6>
J 0
(-1540 4410);
DISPLAY 0.659574 (-1540 4410);
PAINT MONO (-1540 4410);
DISPLAY INVISIBLE (-1540 4410);
FORCEPROP 1 LASTPIN (-1550 4400) BN 6
J 2
(-1538 4408);
DISPLAY 0.680851 (-1538 4408);
PAINT GREEN (-1538 4408);
FORCEPROP 2 LAST CDS_LIB standard
J 0
(-1600 4400);
PAINT MONO (-1600 4400);
DISPLAY INVISIBLE (-1600 4400);
FORCEPROP 1 LAST BODY_TYPE PLUMBING
J 2
(-1600 4450);
DISPLAY 0.872340 (-1600 4450);
PAINT GREEN (-1600 4450);
DISPLAY INVISIBLE (-1600 4450);
FORCEPROP 1 LAST HDL_TAP TRUE
J 2
(-1925 4275);
DISPLAY 0.872340 (-1925 4275);
PAINT GREEN (-1925 4275);
DISPLAY INVISIBLE (-1925 4275);
FORCEPROP 1 LAST PATH I69
J 2
(-1598 4400);
DISPLAY 0.872340 (-1598 4400);
PAINT GREEN (-1598 4400);
DISPLAY INVISIBLE (-1598 4400);
FORCEADD UNIVERSAL_POWER..1
(-4325 2550);
FORCEPROP 3 LASTPIN (-4325 2500) SIG_NAME P3V3_OCP_SFF\g
J 0
(-4315 2510);
DISPLAY 0.659574 (-4315 2510);
PAINT MONO (-4315 2510);
DISPLAY INVISIBLE (-4315 2510);
FORCEPROP 1 LAST HDL_POWER P3V3_OCP_SFF
J 1
(-4325 2600);
DISPLAY 0.872340 (-4325 2600);
PAINT GREEN (-4325 2600);
FORCEPROP 2 LAST CDS_LIB logical_power
J 0
(-4325 2550);
PAINT MONO (-4325 2550);
DISPLAY INVISIBLE (-4325 2550);
FORCEPROP 1 LAST PATH I7
J 0
(-4275 2575);
DISPLAY 0.872340 (-4275 2575);
PAINT AQUA (-4275 2575);
DISPLAY INVISIBLE (-4275 2575);
FORCEADD TAP..1
R 2
(-1600 4700);
FORCEPROP 3 LASTPIN (-1550 4700) SIG_NAME P5E_CPU0_PE1_TX_C_DN<4>
J 0
(-1540 4710);
DISPLAY 0.659574 (-1540 4710);
PAINT MONO (-1540 4710);
DISPLAY INVISIBLE (-1540 4710);
FORCEPROP 1 LASTPIN (-1550 4700) BN 4
J 2
(-1538 4708);
DISPLAY 0.680851 (-1538 4708);
PAINT GREEN (-1538 4708);
FORCEPROP 2 LAST CDS_LIB standard
J 0
(-1600 4700);
PAINT MONO (-1600 4700);
DISPLAY INVISIBLE (-1600 4700);
FORCEPROP 1 LAST BODY_TYPE PLUMBING
J 2
(-1600 4750);
DISPLAY 0.872340 (-1600 4750);
PAINT GREEN (-1600 4750);
DISPLAY INVISIBLE (-1600 4750);
FORCEPROP 1 LAST HDL_TAP TRUE
J 2
(-1925 4575);
DISPLAY 0.872340 (-1925 4575);
PAINT GREEN (-1925 4575);
DISPLAY INVISIBLE (-1925 4575);
FORCEPROP 1 LAST PATH I70
J 2
(-1598 4700);
DISPLAY 0.872340 (-1598 4700);
PAINT GREEN (-1598 4700);
DISPLAY INVISIBLE (-1598 4700);
FORCEADD TAP..1
R 2
(-1600 5150);
FORCEPROP 3 LASTPIN (-1550 5150) SIG_NAME P5E_CPU0_PE1_TX_C_DN<2>
J 0
(-1540 5160);
DISPLAY 0.659574 (-1540 5160);
PAINT MONO (-1540 5160);
DISPLAY INVISIBLE (-1540 5160);
FORCEPROP 1 LASTPIN (-1550 5150) BN 2
J 2
(-1538 5158);
DISPLAY 0.680851 (-1538 5158);
PAINT GREEN (-1538 5158);
FORCEPROP 2 LAST CDS_LIB standard
J 0
(-1600 5150);
PAINT MONO (-1600 5150);
DISPLAY INVISIBLE (-1600 5150);
FORCEPROP 1 LAST BODY_TYPE PLUMBING
J 2
(-1600 5200);
DISPLAY 0.872340 (-1600 5200);
PAINT GREEN (-1600 5200);
DISPLAY INVISIBLE (-1600 5200);
FORCEPROP 1 LAST HDL_TAP TRUE
J 2
(-1925 5025);
DISPLAY 0.872340 (-1925 5025);
PAINT GREEN (-1925 5025);
DISPLAY INVISIBLE (-1925 5025);
FORCEPROP 1 LAST PATH I73
J 2
(-1598 5150);
DISPLAY 0.872340 (-1598 5150);
PAINT GREEN (-1598 5150);
DISPLAY INVISIBLE (-1598 5150);
FORCEADD OFFPAGE..5
(-2350 6450);
FORCEPROP 2 LAST $XR0 154 
J 0
(-2635 6450);
DISPLAY 0.638298 (-2635 6450);
PAINT MONO (-2635 6450);
FORCEPROP 2 LAST CDS_LIB standard
J 0
(-2350 6450);
PAINT MONO (-2350 6450);
DISPLAY INVISIBLE (-2350 6450);
FORCEPROP 1 LAST OFFPAGE TRUE
J 0
(-2025 6325);
DISPLAY 0.872340 (-2025 6325);
PAINT GREEN (-2025 6325);
DISPLAY INVISIBLE (-2025 6325);
FORCEPROP 1 LAST COMMENT_BODY TRUE
J 0
(-2250 6375);
DISPLAY 0.872340 (-2250 6375);
PAINT GREEN (-2250 6375);
DISPLAY INVISIBLE (-2250 6375);
FORCEPROP 2 LAST PATH I76
J 0
(-2650 6500);
DISPLAY 1.021277 (-2650 6500);
DISPLAY INVISIBLE (-2650 6500);
FORCEADD OFFPAGE..1
(-2350 6600);
FORCEPROP 2 LAST $XR0 209 
J 0
(-2602 6600);
DISPLAY 0.638298 (-2602 6600);
PAINT MONO (-2602 6600);
FORCEPROP 2 LAST CDS_LIB standard
J 0
(-2350 6600);
PAINT MONO (-2350 6600);
DISPLAY INVISIBLE (-2350 6600);
FORCEPROP 1 LAST OFFPAGE TRUE
J 0
(-2025 6475);
DISPLAY 0.872340 (-2025 6475);
PAINT GREEN (-2025 6475);
DISPLAY INVISIBLE (-2025 6475);
FORCEPROP 1 LAST COMMENT_BODY TRUE
J 0
(-2225 6500);
DISPLAY 0.872340 (-2225 6500);
PAINT GREEN (-2225 6500);
DISPLAY INVISIBLE (-2225 6500);
FORCEPROP 2 LAST PATH I77
J 0
(-2625 6650);
DISPLAY 1.021277 (-2625 6650);
DISPLAY INVISIBLE (-2625 6650);
FORCEADD OFFPAGE..1
(-2350 6550);
FORCEPROP 2 LAST $XR0 209 
J 0
(-2602 6550);
DISPLAY 0.638298 (-2602 6550);
PAINT MONO (-2602 6550);
FORCEPROP 2 LAST CDS_LIB standard
J 0
(-2350 6550);
PAINT MONO (-2350 6550);
DISPLAY INVISIBLE (-2350 6550);
FORCEPROP 1 LAST OFFPAGE TRUE
J 0
(-2025 6425);
DISPLAY 0.872340 (-2025 6425);
PAINT GREEN (-2025 6425);
DISPLAY INVISIBLE (-2025 6425);
FORCEPROP 1 LAST COMMENT_BODY TRUE
J 0
(-2225 6450);
DISPLAY 0.872340 (-2225 6450);
PAINT GREEN (-2225 6450);
DISPLAY INVISIBLE (-2225 6450);
FORCEPROP 2 LAST PATH I78
J 0
(-2625 6600);
DISPLAY 1.021277 (-2625 6600);
DISPLAY INVISIBLE (-2625 6600);
FORCEADD OFFPAGE..5
(-2350 6750);
FORCEPROP 2 LAST $XR0 154 
J 0
(-2635 6750);
DISPLAY 0.638298 (-2635 6750);
PAINT MONO (-2635 6750);
FORCEPROP 2 LAST CDS_LIB standard
J 0
(-2350 6750);
PAINT MONO (-2350 6750);
DISPLAY INVISIBLE (-2350 6750);
FORCEPROP 1 LAST OFFPAGE TRUE
J 0
(-2025 6625);
DISPLAY 0.872340 (-2025 6625);
PAINT GREEN (-2025 6625);
DISPLAY INVISIBLE (-2025 6625);
FORCEPROP 1 LAST COMMENT_BODY TRUE
J 0
(-2250 6675);
DISPLAY 0.872340 (-2250 6675);
PAINT GREEN (-2250 6675);
DISPLAY INVISIBLE (-2250 6675);
FORCEPROP 2 LAST PATH I79
J 0
(-2650 6800);
DISPLAY 1.021277 (-2650 6800);
DISPLAY INVISIBLE (-2650 6800);
FORCEADD OFFPAGE..2
(-3250 2000);
FORCEPROP 2 LAST $XR0 153 
J 0
(-3061 2000);
DISPLAY 0.638298 (-3061 2000);
PAINT MONO (-3061 2000);
FORCEPROP 2 LAST CDS_LIB standard
J 0
(-3250 2000);
PAINT MONO (-3250 2000);
DISPLAY INVISIBLE (-3250 2000);
FORCEPROP 1 LAST OFFPAGE TRUE
J 0
(-2925 1875);
DISPLAY 0.872340 (-2925 1875);
PAINT GREEN (-2925 1875);
DISPLAY INVISIBLE (-2925 1875);
FORCEPROP 1 LAST COMMENT_BODY TRUE
J 0
(-3295 1905);
DISPLAY 0.872340 (-3295 1905);
PAINT GREEN (-3295 1905);
DISPLAY INVISIBLE (-3295 1905);
FORCEPROP 2 LAST PATH I8
J 0
(-3050 2050);
DISPLAY 1.021277 (-3050 2050);
DISPLAY INVISIBLE (-3050 2050);
FORCEADD OFFPAGE..5
(-2350 6700);
FORCEPROP 2 LAST $XR0 154 
J 0
(-2635 6700);
DISPLAY 0.638298 (-2635 6700);
PAINT MONO (-2635 6700);
FORCEPROP 2 LAST CDS_LIB standard
J 0
(-2350 6700);
PAINT MONO (-2350 6700);
DISPLAY INVISIBLE (-2350 6700);
FORCEPROP 1 LAST OFFPAGE TRUE
J 0
(-2025 6575);
DISPLAY 0.872340 (-2025 6575);
PAINT GREEN (-2025 6575);
DISPLAY INVISIBLE (-2025 6575);
FORCEPROP 1 LAST COMMENT_BODY TRUE
J 0
(-2250 6625);
DISPLAY 0.872340 (-2250 6625);
PAINT GREEN (-2250 6625);
DISPLAY INVISIBLE (-2250 6625);
FORCEPROP 2 LAST PATH I80
J 0
(-2650 6750);
DISPLAY 1.021277 (-2650 6750);
DISPLAY INVISIBLE (-2650 6750);
FORCEADD OFFPAGE..1
(-2350 6800);
FORCEPROP 2 LAST $XR0 153 
J 0
(-2632 6800);
DISPLAY 0.638298 (-2632 6800);
PAINT MONO (-2632 6800);
FORCEPROP 2 LAST CDS_LIB standard
J 0
(-2350 6800);
PAINT MONO (-2350 6800);
DISPLAY INVISIBLE (-2350 6800);
FORCEPROP 1 LAST OFFPAGE TRUE
J 0
(-2025 6675);
DISPLAY 0.872340 (-2025 6675);
PAINT GREEN (-2025 6675);
DISPLAY INVISIBLE (-2025 6675);
FORCEPROP 1 LAST COMMENT_BODY TRUE
J 0
(-2225 6700);
DISPLAY 0.872340 (-2225 6700);
PAINT GREEN (-2225 6700);
DISPLAY INVISIBLE (-2225 6700);
FORCEPROP 2 LAST PATH I81
J 0
(-2650 6850);
DISPLAY 1.021277 (-2650 6850);
DISPLAY INVISIBLE (-2650 6850);
FORCEADD OFFPAGE..5
(-2350 6850);
FORCEPROP 2 LAST $XR1 213 
J 0
(-2755 6850);
DISPLAY 0.638298 (-2755 6850);
PAINT MONO (-2755 6850);
FORCEPROP 2 LAST $XR0 153 
J 0
(-2635 6850);
DISPLAY 0.638298 (-2635 6850);
PAINT MONO (-2635 6850);
FORCEPROP 2 LAST CDS_LIB standard
J 0
(-2350 6850);
PAINT MONO (-2350 6850);
DISPLAY INVISIBLE (-2350 6850);
FORCEPROP 1 LAST OFFPAGE TRUE
J 0
(-2025 6725);
DISPLAY 0.872340 (-2025 6725);
PAINT GREEN (-2025 6725);
DISPLAY INVISIBLE (-2025 6725);
FORCEPROP 1 LAST COMMENT_BODY TRUE
J 0
(-2250 6775);
DISPLAY 0.872340 (-2250 6775);
PAINT GREEN (-2250 6775);
DISPLAY INVISIBLE (-2250 6775);
FORCEPROP 2 LAST PATH I82
J 0
(-2650 6900);
DISPLAY 1.021277 (-2650 6900);
DISPLAY INVISIBLE (-2650 6900);
FORCEADD OFFPAGE..1
(-2350 6900);
FORCEPROP 2 LAST $XR1 213 
J 0
(-2722 6900);
DISPLAY 0.638298 (-2722 6900);
PAINT MONO (-2722 6900);
FORCEPROP 2 LAST $XR0 153 
J 0
(-2602 6900);
DISPLAY 0.638298 (-2602 6900);
PAINT MONO (-2602 6900);
FORCEPROP 2 LAST CDS_LIB standard
J 0
(-2350 6900);
PAINT MONO (-2350 6900);
DISPLAY INVISIBLE (-2350 6900);
FORCEPROP 1 LAST OFFPAGE TRUE
J 0
(-2025 6775);
DISPLAY 0.872340 (-2025 6775);
PAINT GREEN (-2025 6775);
DISPLAY INVISIBLE (-2025 6775);
FORCEPROP 1 LAST COMMENT_BODY TRUE
J 0
(-2225 6800);
DISPLAY 0.872340 (-2225 6800);
PAINT GREEN (-2225 6800);
DISPLAY INVISIBLE (-2225 6800);
FORCEPROP 2 LAST PATH I83
J 0
(-2625 6950);
DISPLAY 1.021277 (-2625 6950);
DISPLAY INVISIBLE (-2625 6950);
FORCEADD OFFPAGE..1
(-2350 6950);
FORCEPROP 2 LAST $XR1 213 
J 0
(-2722 6950);
DISPLAY 0.638298 (-2722 6950);
PAINT MONO (-2722 6950);
FORCEPROP 2 LAST $XR0 153 
J 0
(-2602 6950);
DISPLAY 0.638298 (-2602 6950);
PAINT MONO (-2602 6950);
FORCEPROP 2 LAST CDS_LIB standard
J 0
(-2350 6950);
PAINT MONO (-2350 6950);
DISPLAY INVISIBLE (-2350 6950);
FORCEPROP 1 LAST OFFPAGE TRUE
J 0
(-2025 6825);
DISPLAY 0.872340 (-2025 6825);
PAINT GREEN (-2025 6825);
DISPLAY INVISIBLE (-2025 6825);
FORCEPROP 1 LAST COMMENT_BODY TRUE
J 0
(-2225 6850);
DISPLAY 0.872340 (-2225 6850);
PAINT GREEN (-2225 6850);
DISPLAY INVISIBLE (-2225 6850);
FORCEPROP 2 LAST PATH I84
J 0
(-2625 7000);
DISPLAY 1.021277 (-2625 7000);
DISPLAY INVISIBLE (-2625 7000);
FORCEADD OFFPAGE..1
(-2350 7000);
FORCEPROP 2 LAST $XR1 213 
J 0
(-2722 7000);
DISPLAY 0.638298 (-2722 7000);
PAINT MONO (-2722 7000);
FORCEPROP 2 LAST $XR0 153 
J 0
(-2602 7000);
DISPLAY 0.638298 (-2602 7000);
PAINT MONO (-2602 7000);
FORCEPROP 2 LAST CDS_LIB standard
J 0
(-2350 7000);
PAINT MONO (-2350 7000);
DISPLAY INVISIBLE (-2350 7000);
FORCEPROP 1 LAST OFFPAGE TRUE
J 0
(-2025 6875);
DISPLAY 0.872340 (-2025 6875);
PAINT GREEN (-2025 6875);
DISPLAY INVISIBLE (-2025 6875);
FORCEPROP 1 LAST COMMENT_BODY TRUE
J 0
(-2225 6900);
DISPLAY 0.872340 (-2225 6900);
PAINT GREEN (-2225 6900);
DISPLAY INVISIBLE (-2225 6900);
FORCEPROP 2 LAST PATH I85
J 0
(-2625 7050);
DISPLAY 1.021277 (-2625 7050);
DISPLAY INVISIBLE (-2625 7050);
FORCEADD UNIVERSAL_GND..1
(-225 1325);
FORCEPROP 3 LASTPIN (-225 1375) SIG_NAME GND\g
J 0
(-215 1385);
DISPLAY 0.659574 (-215 1385);
PAINT MONO (-215 1385);
DISPLAY INVISIBLE (-215 1385);
FORCEPROP 2 LAST CDS_LIB logical_power
J 0
(-225 1325);
PAINT MONO (-225 1325);
DISPLAY INVISIBLE (-225 1325);
FORCEPROP 1 LAST HDL_POWER GND
J 1
(-200 1250);
DISPLAY 0.872340 (-200 1250);
PAINT GREEN (-200 1250);
DISPLAY INVISIBLE (-200 1250);
FORCEPROP 1 LAST PATH I88
J 0
(-150 1325);
DISPLAY 0.872340 (-150 1325);
PAINT AQUA (-150 1325);
DISPLAY INVISIBLE (-150 1325);
FORCEPROP 2 LAST ROOM IO_SLOT
J 1
(-450 1400);
DISPLAY 0.744681 (-450 1400);
DISPLAY INVISIBLE (-450 1400);
FORCEADD Q_CAP..1
(800 1750);
FORCEPROP 1 LAST PART_NUMBER CH6223MEA00
J 0
(850 1550);
DISPLAY 0.808511 (850 1550);
DISPLAY INVISIBLE (850 1550);
FORCEPROP 1 LAST MATERIAL X6S
J 0
(850 1650);
DISPLAY 0.638298 (850 1650);
FORCEPROP 1 LAST PACK_TYPE C0805
J 0
(850 1600);
DISPLAY 0.638298 (850 1600);
FORCEPROP 1 LAST TOLERANCE 20%
J 0
(850 1700);
DISPLAY 0.638298 (850 1700);
FORCEPROP 1 LAST VOLTAGE 16V
J 0
(850 1750);
DISPLAY 0.638298 (850 1750);
FORCEPROP 1 LAST VALUE 22UF
J 0
(850 1800);
DISPLAY 0.638298 (850 1800);
FORCEPROP 1 LAST $LOCATION C1213
J 0
(850 1850);
DISPLAY 0.787234 (850 1850);
FORCEPROP 1 LASTPIN (800 1850) $PN 1
J 0
(810 1830);
DISPLAY 0.787234 (810 1830);
FORCEPROP 1 LASTPIN (800 1650) $PN 2
J 0
(810 1630);
DISPLAY 0.787234 (810 1630);
FORCEPROP 2 LAST CDS_LIB pure_quanta
J 0
(800 1750);
PAINT MONO (800 1750);
DISPLAY INVISIBLE (800 1750);
FORCEPROP 1 LAST PATH I89
J 0
(850 1900);
DISPLAY 0.978723 (850 1900);
PAINT WHITE (850 1900);
DISPLAY INVISIBLE (850 1900);
FORCEPROP 2 LAST CDS_LOCATION C1213
J 0
(850 1950);
DISPLAY 1.021277 (850 1950);
DISPLAY INVISIBLE (850 1950);
FORCEPROP 2 LAST $SEC 1
J 0
(850 1950);
DISPLAY 0.680851 (850 1950);
PAINT MONO (850 1950);
DISPLAY INVISIBLE (850 1950);
FORCEPROP 2 LAST CDS_SEC 1
J 0
(850 1950);
DISPLAY 1.021277 (850 1950);
DISPLAY INVISIBLE (850 1950);
FORCEADD OFFPAGE..2
(-3250 1950);
FORCEPROP 2 LAST $XR0 153 
J 0
(-3061 1950);
DISPLAY 0.638298 (-3061 1950);
PAINT MONO (-3061 1950);
FORCEPROP 2 LAST CDS_LIB standard
J 0
(-3250 1950);
PAINT MONO (-3250 1950);
DISPLAY INVISIBLE (-3250 1950);
FORCEPROP 1 LAST OFFPAGE TRUE
J 0
(-2925 1825);
DISPLAY 0.872340 (-2925 1825);
PAINT GREEN (-2925 1825);
DISPLAY INVISIBLE (-2925 1825);
FORCEPROP 1 LAST COMMENT_BODY TRUE
J 0
(-3295 1855);
DISPLAY 0.872340 (-3295 1855);
PAINT GREEN (-3295 1855);
DISPLAY INVISIBLE (-3295 1855);
FORCEPROP 2 LAST PATH I9
J 0
(-3050 2000);
DISPLAY 1.021277 (-3050 2000);
DISPLAY INVISIBLE (-3050 2000);
FORCEADD Q_CAP..1
(1075 1750);
FORCEPROP 1 LAST PART_NUMBER CH6223MEA00
J 0
(1125 1600);
DISPLAY 0.638298 (1125 1600);
DISPLAY INVISIBLE (1125 1600);
FORCEPROP 1 LAST PACK_TYPE C0805
J 0
(1125 1550);
DISPLAY 0.638298 (1125 1550);
FORCEPROP 1 LAST VALUE 22UF
J 0
(1125 1800);
DISPLAY 0.638298 (1125 1800);
FORCEPROP 1 LAST TOLERANCE 20%
J 0
(1125 1700);
DISPLAY 0.638298 (1125 1700);
FORCEPROP 1 LAST MATERIAL X6S
J 0
(1125 1650);
DISPLAY 0.638298 (1125 1650);
FORCEPROP 1 LAST VOLTAGE 16V
J 0
(1125 1750);
DISPLAY 0.638298 (1125 1750);
FORCEPROP 1 LAST $LOCATION C1232
J 0
(1125 1850);
DISPLAY 0.787234 (1125 1850);
FORCEPROP 1 LASTPIN (1075 1850) $PN 1
J 0
(1085 1830);
DISPLAY 0.787234 (1085 1830);
FORCEPROP 1 LASTPIN (1075 1650) $PN 2
J 0
(1085 1630);
DISPLAY 0.787234 (1085 1630);
FORCEPROP 2 LAST CDS_LIB pure_quanta
J 0
(1075 1750);
PAINT MONO (1075 1750);
DISPLAY INVISIBLE (1075 1750);
FORCEPROP 1 LAST PATH I90
J 0
(1125 1900);
DISPLAY 0.978723 (1125 1900);
PAINT WHITE (1125 1900);
DISPLAY INVISIBLE (1125 1900);
FORCEPROP 2 LAST CDS_LOCATION C1232
J 0
(1125 1950);
DISPLAY 1.021277 (1125 1950);
DISPLAY INVISIBLE (1125 1950);
FORCEPROP 2 LAST $SEC 1
J 0
(1125 1950);
DISPLAY 0.680851 (1125 1950);
PAINT MONO (1125 1950);
DISPLAY INVISIBLE (1125 1950);
FORCEPROP 2 LAST CDS_SEC 1
J 0
(1125 1950);
DISPLAY 1.021277 (1125 1950);
DISPLAY INVISIBLE (1125 1950);
FORCEADD Q_CAP..1
(1475 1750);
FORCEPROP 1 LAST PART_NUMBER CH4104K1B00
J 0
(1525 1600);
DISPLAY 0.808511 (1525 1600);
DISPLAY INVISIBLE (1525 1600);
FORCEPROP 1 LAST TOLERANCE 10%
J 0
(1525 1700);
DISPLAY 0.638298 (1525 1700);
FORCEPROP 1 LAST VOLTAGE 25V
J 0
(1525 1750);
DISPLAY 0.638298 (1525 1750);
FORCEPROP 1 LAST VALUE 0.1UF
J 0
(1525 1800);
DISPLAY 0.638298 (1525 1800);
FORCEPROP 1 LAST MATERIAL X7R
J 0
(1525 1650);
DISPLAY 0.638298 (1525 1650);
FORCEPROP 1 LAST PACK_TYPE 0402
J 0
(1525 1600);
DISPLAY 0.638298 (1525 1600);
FORCEPROP 1 LAST $LOCATION C1233
J 0
(1525 1850);
DISPLAY 0.787234 (1525 1850);
FORCEPROP 1 LASTPIN (1475 1850) $PN 1
J 0
(1485 1830);
DISPLAY 0.787234 (1485 1830);
FORCEPROP 1 LASTPIN (1475 1650) $PN 2
J 0
(1485 1630);
DISPLAY 0.787234 (1485 1630);
FORCEPROP 2 LAST CDS_LIB pure_quanta
J 0
(1475 1750);
PAINT MONO (1475 1750);
DISPLAY INVISIBLE (1475 1750);
FORCEPROP 1 LAST PATH I91
J 0
(1525 1900);
DISPLAY 0.978723 (1525 1900);
PAINT WHITE (1525 1900);
DISPLAY INVISIBLE (1525 1900);
FORCEPROP 2 LAST CDS_LOCATION C1233
J 0
(1525 1950);
DISPLAY 1.021277 (1525 1950);
DISPLAY INVISIBLE (1525 1950);
FORCEPROP 2 LAST $SEC 1
J 0
(1525 1950);
DISPLAY 0.680851 (1525 1950);
PAINT MONO (1525 1950);
DISPLAY INVISIBLE (1525 1950);
FORCEPROP 2 LAST CDS_SEC 1
J 0
(1525 1950);
DISPLAY 1.021277 (1525 1950);
DISPLAY INVISIBLE (1525 1950);
FORCEADD UNIVERSAL_POWER..1
(-225 2125);
FORCEPROP 3 LASTPIN (-225 2075) SIG_NAME P3V3_OCP_SFF\g
J 0
(-215 2085);
DISPLAY 0.659574 (-215 2085);
PAINT MONO (-215 2085);
DISPLAY INVISIBLE (-215 2085);
FORCEPROP 1 LAST HDL_POWER P3V3_OCP_SFF
J 1
(-225 2175);
DISPLAY 0.872340 (-225 2175);
PAINT GREEN (-225 2175);
FORCEPROP 2 LAST CDS_LIB logical_power
J 0
(-225 2125);
PAINT MONO (-225 2125);
DISPLAY INVISIBLE (-225 2125);
FORCEPROP 1 LAST PATH I92
J 0
(-175 2150);
DISPLAY 0.872340 (-175 2150);
PAINT AQUA (-175 2150);
DISPLAY INVISIBLE (-175 2150);
FORCEADD UNIVERSAL_POWER..1
(800 2100);
FORCEPROP 3 LASTPIN (800 2050) SIG_NAME P12V_OCP_SFF\g
J 0
(810 2060);
DISPLAY 0.659574 (810 2060);
PAINT MONO (810 2060);
DISPLAY INVISIBLE (810 2060);
FORCEPROP 1 LAST HDL_POWER P12V_OCP_SFF
J 1
(850 2150);
DISPLAY 0.872340 (850 2150);
PAINT GREEN (850 2150);
FORCEPROP 2 LAST CDS_LIB logical_power
J 0
(800 2100);
PAINT MONO (800 2100);
DISPLAY INVISIBLE (800 2100);
FORCEPROP 1 LAST PATH I93
J 0
(850 2125);
DISPLAY 0.872340 (850 2125);
PAINT AQUA (850 2125);
DISPLAY INVISIBLE (850 2125);
FORCEADD UNIVERSAL_GND..1
(550 2225);
FORCEPROP 3 LASTPIN (550 2275) SIG_NAME GND\g
J 0
(560 2285);
DISPLAY 0.659574 (560 2285);
PAINT MONO (560 2285);
DISPLAY INVISIBLE (560 2285);
FORCEPROP 2 LAST CDS_LIB logical_power
J 0
(550 2225);
PAINT MONO (550 2225);
DISPLAY INVISIBLE (550 2225);
FORCEPROP 1 LAST HDL_POWER GND
J 1
(575 2150);
DISPLAY 0.872340 (575 2150);
PAINT GREEN (575 2150);
DISPLAY INVISIBLE (575 2150);
FORCEPROP 1 LAST PATH I94
J 0
(625 2225);
DISPLAY 0.872340 (625 2225);
PAINT AQUA (625 2225);
DISPLAY INVISIBLE (625 2225);
FORCEPROP 2 LAST ROOM IO_SLOT
J 1
(325 2300);
DISPLAY 0.744681 (325 2300);
DISPLAY INVISIBLE (325 2300);
FORCEADD TAP..1
(750 2850);
FORCEPROP 3 LASTPIN (700 2850) SIG_NAME P5E_CPU0_PE1_RX_DN<15>
J 0
(710 2860);
DISPLAY 0.659574 (710 2860);
PAINT MONO (710 2860);
DISPLAY INVISIBLE (710 2860);
FORCEPROP 1 LASTPIN (700 2850) BN 15
J 0
(688 2858);
DISPLAY 0.680851 (688 2858);
PAINT GREEN (688 2858);
FORCEPROP 2 LAST CDS_LIB standard
J 0
(750 2850);
PAINT MONO (750 2850);
DISPLAY INVISIBLE (750 2850);
FORCEPROP 1 LAST BODY_TYPE PLUMBING
J 0
(750 2900);
DISPLAY 0.872340 (750 2900);
PAINT GREEN (750 2900);
DISPLAY INVISIBLE (750 2900);
FORCEPROP 1 LAST HDL_TAP TRUE
J 0
(1075 2725);
DISPLAY 0.872340 (1075 2725);
PAINT GREEN (1075 2725);
DISPLAY INVISIBLE (1075 2725);
FORCEPROP 1 LAST PATH I95
J 0
(748 2850);
DISPLAY 0.872340 (748 2850);
PAINT GREEN (748 2850);
DISPLAY INVISIBLE (748 2850);
FORCEADD TAP..1
(900 2900);
FORCEPROP 3 LASTPIN (850 2900) SIG_NAME P5E_CPU0_PE1_RX_DP<15>
J 0
(860 2910);
DISPLAY 0.659574 (860 2910);
PAINT MONO (860 2910);
DISPLAY INVISIBLE (860 2910);
FORCEPROP 1 LASTPIN (850 2900) BN 15
J 0
(838 2908);
DISPLAY 0.680851 (838 2908);
PAINT GREEN (838 2908);
FORCEPROP 2 LAST CDS_LIB standard
J 0
(900 2900);
PAINT MONO (900 2900);
DISPLAY INVISIBLE (900 2900);
FORCEPROP 1 LAST BODY_TYPE PLUMBING
J 0
(900 2950);
DISPLAY 0.872340 (900 2950);
PAINT GREEN (900 2950);
DISPLAY INVISIBLE (900 2950);
FORCEPROP 1 LAST HDL_TAP TRUE
J 0
(1225 2775);
DISPLAY 0.872340 (1225 2775);
PAINT GREEN (1225 2775);
DISPLAY INVISIBLE (1225 2775);
FORCEPROP 1 LAST PATH I96
J 0
(898 2900);
DISPLAY 0.872340 (898 2900);
PAINT GREEN (898 2900);
DISPLAY INVISIBLE (898 2900);
FORCEADD TAP..1
(750 3000);
FORCEPROP 3 LASTPIN (700 3000) SIG_NAME P5E_CPU0_PE1_RX_DN<14>
J 0
(710 3010);
DISPLAY 0.659574 (710 3010);
PAINT MONO (710 3010);
DISPLAY INVISIBLE (710 3010);
FORCEPROP 1 LASTPIN (700 3000) BN 14
J 0
(688 3008);
DISPLAY 0.680851 (688 3008);
PAINT GREEN (688 3008);
FORCEPROP 2 LAST CDS_LIB standard
J 0
(750 3000);
PAINT MONO (750 3000);
DISPLAY INVISIBLE (750 3000);
FORCEPROP 1 LAST BODY_TYPE PLUMBING
J 0
(750 3050);
DISPLAY 0.872340 (750 3050);
PAINT GREEN (750 3050);
DISPLAY INVISIBLE (750 3050);
FORCEPROP 1 LAST HDL_TAP TRUE
J 0
(1075 2875);
DISPLAY 0.872340 (1075 2875);
PAINT GREEN (1075 2875);
DISPLAY INVISIBLE (1075 2875);
FORCEPROP 1 LAST PATH I97
J 0
(748 3000);
DISPLAY 0.872340 (748 3000);
PAINT GREEN (748 3000);
DISPLAY INVISIBLE (748 3000);
FORCEADD TAP..1
(750 3150);
FORCEPROP 3 LASTPIN (700 3150) SIG_NAME P5E_CPU0_PE1_RX_DN<13>
J 0
(710 3160);
DISPLAY 0.659574 (710 3160);
PAINT MONO (710 3160);
DISPLAY INVISIBLE (710 3160);
FORCEPROP 1 LASTPIN (700 3150) BN 13
J 0
(688 3158);
DISPLAY 0.680851 (688 3158);
PAINT GREEN (688 3158);
FORCEPROP 2 LAST CDS_LIB standard
J 0
(750 3150);
PAINT MONO (750 3150);
DISPLAY INVISIBLE (750 3150);
FORCEPROP 1 LAST BODY_TYPE PLUMBING
J 0
(750 3200);
DISPLAY 0.872340 (750 3200);
PAINT GREEN (750 3200);
DISPLAY INVISIBLE (750 3200);
FORCEPROP 1 LAST HDL_TAP TRUE
J 0
(1075 3025);
DISPLAY 0.872340 (1075 3025);
PAINT GREEN (1075 3025);
DISPLAY INVISIBLE (1075 3025);
FORCEPROP 1 LAST PATH I98
J 0
(748 3150);
DISPLAY 0.872340 (748 3150);
PAINT GREEN (748 3150);
DISPLAY INVISIBLE (748 3150);
FORCEADD TAP..1
(750 3300);
FORCEPROP 3 LASTPIN (700 3300) SIG_NAME P5E_CPU0_PE1_RX_DN<12>
J 0
(710 3310);
DISPLAY 0.659574 (710 3310);
PAINT MONO (710 3310);
DISPLAY INVISIBLE (710 3310);
FORCEPROP 1 LASTPIN (700 3300) BN 12
J 0
(688 3308);
DISPLAY 0.680851 (688 3308);
PAINT GREEN (688 3308);
FORCEPROP 2 LAST CDS_LIB standard
J 0
(750 3300);
PAINT MONO (750 3300);
DISPLAY INVISIBLE (750 3300);
FORCEPROP 1 LAST BODY_TYPE PLUMBING
J 0
(750 3350);
DISPLAY 0.872340 (750 3350);
PAINT GREEN (750 3350);
DISPLAY INVISIBLE (750 3350);
FORCEPROP 1 LAST HDL_TAP TRUE
J 0
(1075 3175);
DISPLAY 0.872340 (1075 3175);
PAINT GREEN (1075 3175);
DISPLAY INVISIBLE (1075 3175);
FORCEPROP 1 LAST PATH I99
J 0
(748 3300);
DISPLAY 0.872340 (748 3300);
PAINT GREEN (748 3300);
DISPLAY INVISIBLE (748 3300);
FORCEADD CAD_NOTE..1
(1425 2150);
FORCEPROP 0 LAST S1 PLACE THE BULK CAPS CLOSE TO SLOT
J 0
(1275 2025);
DISPLAY 0.808511 (1275 2025);
PAINT WHITE (1275 2025);
FORCEPROP 2 LAST CDS_LIB logical_power
J 0
(1425 2150);
PAINT MONO (1425 2150);
DISPLAY INVISIBLE (1425 2150);
FORCEPROP 1 LAST COMMENT_BODY TRUE
J 0
(1450 2250);
DISPLAY 0.978723 (1450 2250);
DISPLAY INVISIBLE (1450 2250);
FORCEADD DNS..2
(-3850 2225);
PAINT RED (-3850 2225);
FORCEPROP 2 LAST CDS_LIB mstr_misc
J 0
(-3850 2225);
PAINT MONO (-3850 2225);
DISPLAY INVISIBLE (-3850 2225);
FORCEPROP 1 LAST COMMENT_BODY TRUE
R 1
J 0
(-3775 2000);
DISPLAY 0.872340 (-3775 2000);
PAINT GREEN (-3775 2000);
DISPLAY INVISIBLE (-3775 2000);
FORCEADD DNS..2
(-4325 2225);
PAINT RED (-4325 2225);
FORCEPROP 2 LAST CDS_LIB mstr_misc
J 0
(-4325 2225);
PAINT MONO (-4325 2225);
DISPLAY INVISIBLE (-4325 2225);
FORCEPROP 1 LAST COMMENT_BODY TRUE
R 1
J 0
(-4250 2000);
DISPLAY 0.872340 (-4250 2000);
PAINT GREEN (-4250 2000);
DISPLAY INVISIBLE (-4250 2000);
FORCEADD QUANTA_TITLE_BLOCK_C..1
(4375 1025);
FORCEPROP 0 LAST CDS_CON_LAST_MODIFIED Fri Aug 25 14:02:15 2023
J 0
(2490 1040);
PAINT MONO (2490 1040);
DISPLAY INVISIBLE (2490 1040);
FORCEPROP 2 LAST CUSTOM_TXT_CDS <XR_PAGE_TITLE>
J 0
(-3515 6275);
DISPLAY 0.638298 (-3515 6275);
PAINT PINK (-3515 6275);
DISPLAY INVISIBLE (-3515 6275);
FORCEPROP 2 LAST CUSTOM_TXT_CDS <NAME_1>
J 0
(1200 1200);
FORCEPROP 2 LAST CUSTOM_TXT_CDS <CON_LAST_MODIFIED>
J 0
(2490 1040);
DISPLAY 0.978723 (2490 1040);
FORCEPROP 2 LAST CUSTOM_TXT_CDS <Q_NUMBER>
J 0
(2972 1128);
DISPLAY 1.212766 (2972 1128);
FORCEPROP 2 LAST CUSTOM_TXT_CDS <CON_PAGE_NUM> OF <CON_TOTAL_PAGES>
J 0
(3929 1043);
DISPLAY 0.978723 (3929 1043);
FORCEPROP 2 LAST CUSTOM_TXT_CDS <Q_REV>
J 0
(4191 1128);
DISPLAY 1.212766 (4191 1128);
FORCEPROP 2 LAST CUSTOM_TXT_CDS <Q_PROJ>
J 0
(1993 1127);
DISPLAY 1.212766 (1993 1127);
FORCEPROP 2 LAST CUSTOM_TXT_CDS <NAME_2>
J 0
(1200 1075);
FORCEPROP 1 LAST Q_TITLE PCIE - SFF OCP3.0_X16 (1/3)
J 0
(-4966 1051);
DISPLAY 1.957447 (-4966 1051);
PAINT GREEN (-4966 1051);
FORCEPROP 1 LAST Q_DEPT 
J 1
(612 1074);
DISPLAY 1.957447 (612 1074);
PAINT GREEN (612 1074);
FORCEPROP 2 LAST CDS_XR_PAGE_TITLE CR-153 : @S9S_MB_2U_LIB.S9S_MB_2U(SCH_1):PAGE153
J 0
(-3515 6275);
DISPLAY 0.638298 (-3515 6275);
PAINT PINK (-3515 6275);
DISPLAY INVISIBLE (-3515 6275);
FORCEPROP 1 LAST COMMENT_BODY TRUE
J 0
(4387 1012);
DISPLAY 0.978723 (4387 1012);
PAINT GREEN (4387 1012);
DISPLAY INVISIBLE (4387 1012);
FORCEPROP 2 LAST CDS_LIB pure_quanta
J 0
(4375 1025);
PAINT MONO (4375 1025);
DISPLAY INVISIBLE (4375 1025);
FORCEPROP 1 LAST CDS_LMAN_SYM_OUTLINE -9475,6775,100,-125
J 0
(4375 1025);
DISPLAY 0.468085 (4375 1025);
PAINT GREEN (4375 1025);
DISPLAY INVISIBLE (4375 1025);
FORCEPROP 2 LAST PAGE_BORDER TRUE
J 0
(-3515 6275);
DISPLAY 0.638298 (-3515 6275);
PAINT PINK (-3515 6275);
DISPLAY INVISIBLE (-3515 6275);
WIRE 17 -1 (950 5225)(950 5375);
WIRE 17 -1 (950 5225)(950 5075);
WIRE 17 -1 (950 5475)(950 5375);
WIRE 17 -1 (1900 5475)(950 5475);
FORCEPROP 2 LAST SIG_NAME P5E_CPU0_PE1_RX_DP<15:0>
J 0
(1040 5485);
DISPLAY 0.638298 (1040 5485);
PAINT WHITE (1040 5485);
WIRE 17 -1 (800 5025)(800 5175);
WIRE 17 -1 (800 4725)(800 5025);
WIRE 17 -1 (800 5325)(800 5175);
WIRE 17 -1 (800 5325)(800 5525);
WIRE 17 -1 (800 4575)(800 4725);
WIRE 17 -1 (800 4425)(800 4575);
WIRE 17 -1 (1900 5525)(800 5525);
FORCEPROP 2 LAST SIG_NAME P5E_CPU0_PE1_RX_DN<15:0>
J 0
(1040 5535);
DISPLAY 0.638298 (1040 5535);
PAINT WHITE (1040 5535);
WIRE 17 -1 (-1650 5375)(-1650 5525);
WIRE 17 -1 (-1650 5175)(-1650 5375);
WIRE 17 -1 (-2750 5525)(-1650 5525);
FORCEPROP 2 LAST SIG_NAME P5E_CPU0_PE1_TX_C_DN<15:0>
J 0
(-2685 5535);
DISPLAY 0.680851 (-2685 5535);
PAINT WHITE (-2685 5535);
WIRE 17 -1 (-1800 5325)(-1800 5475);
WIRE 17 -1 (-1800 5225)(-1800 5325);
WIRE 17 -1 (-1800 5475)(-2750 5475);
FORCEPROP 2 LAST SIG_NAME P5E_CPU0_PE1_TX_C_DP<15:0>
J 0
(-2685 5485);
DISPLAY 0.680851 (-2685 5485);
PAINT WHITE (-2685 5485);
WIRE 17 -1 (-1800 4775)(-1800 5025);
WIRE 17 -1 (-1800 4575)(-1800 4775);
WIRE 17 -1 (-1800 5025)(-1800 5225);
WIRE 17 -1 (-1800 4475)(-1800 4575);
WIRE 17 -1 (-1800 4275)(-1800 4475);
WIRE 17 -1 (950 4775)(950 5075);
WIRE 17 -1 (950 4625)(950 4775);
WIRE 17 -1 (950 4475)(950 4625);
WIRE 17 -1 (950 4325)(950 4475);
WIRE 17 -1 (-1800 3975)(-1800 4275);
WIRE 17 -1 (-1800 3975)(-1800 3775);
WIRE 17 -1 (-1800 3775)(-1800 3675);
WIRE 17 -1 (-1800 3675)(-1800 3475);
WIRE 17 -1 (-1800 3475)(-1800 3375);
WIRE 17 -1 (-1800 3375)(-1800 3175);
WIRE 17 -1 (-1800 3175)(-1800 3075);
WIRE 17 -1 (-1650 4325)(-1650 4425);
WIRE 17 -1 (-1650 3925)(-1650 4325);
WIRE 17 -1 (-1650 4425)(-1650 4625);
WIRE 17 -1 (-1650 4625)(-1650 4725);
WIRE 17 -1 (-1650 3825)(-1650 3925);
WIRE 17 -1 (-1650 3625)(-1650 3825);
WIRE 17 -1 (-1650 4725)(-1650 5075);
WIRE 17 -1 (-1650 5075)(-1650 5175);
WIRE 17 -1 (-1650 3525)(-1650 3625);
WIRE 17 -1 (-1650 3325)(-1650 3525);
WIRE 17 -1 (-1650 3325)(-1650 3225);
WIRE 17 -1 (-1650 3225)(-1650 3025);
WIRE 17 -1 (-1800 3075)(-1800 2875);
WIRE 17 -1 (-1650 2925)(-1650 3025);
WIRE 17 -1 (950 2925)(950 3075);
WIRE 17 -1 (950 3225)(950 3075);
WIRE 17 -1 (950 3375)(950 3225);
WIRE 17 -1 (950 3525)(950 3375);
WIRE 17 -1 (950 3675)(950 3525);
WIRE 17 -1 (950 3675)(950 3825);
WIRE 17 -1 (950 3825)(950 3975);
WIRE 17 -1 (950 3975)(950 4325);
WIRE 17 -1 (800 2875)(800 3025);
WIRE 17 -1 (800 3175)(800 3025);
WIRE 17 -1 (800 3325)(800 3175);
WIRE 17 -1 (800 3475)(800 3325);
WIRE 17 -1 (800 3625)(800 3475);
WIRE 17 -1 (800 3625)(800 3775);
WIRE 17 -1 (800 3775)(800 3925);
WIRE 17 -1 (800 3925)(800 4275);
WIRE 17 -1 (800 4425)(800 4275);
WIRE 16 -1 (-4325 2500)(-4325 2450);
WIRE 16 -1 (2825 2200)(2825 2125);
WIRE 16 -1 (-1450 7350)(-1450 6300);
WIRE 16 -1 (800 2050)(800 1975);
WIRE 16 -1 (-225 2075)(-225 1975);
WIRE 16 -1 (-2275 6125)(-2275 5800);
WIRE 16 -1 (3625 1600)(3625 1675);
WIRE 16 -1 (-225 1375)(-225 1450);
WIRE 16 -1 (-4325 1550)(-4325 1625);
WIRE 16 -1 (-3850 1550)(-3850 1625);
WIRE 16 -1 (-4675 4425)(-4675 4375);
WIRE 16 -1 (-4675 4625)(-4675 4425);
WIRE 16 -1 (-4350 4425)(-4675 4425);
WIRE 16 -1 (-1375 2550)(-1375 2800);
WIRE 16 -1 (3100 5375)(3100 5500);
WIRE 16 -1 (550 2275)(550 2350);
WIRE 16 -1 (2300 1450)(2300 1525);
WIRE 16 -1 (275 6600)(1350 6600);
FORCEPROP 2 LAST SIG_NAME CLK_100M_OCP_SFF_3_DN
J 0
(640 6610);
DISPLAY 0.510638 (640 6610);
PAINT WHITE (640 6610);
WIRE 16 -1 (275 6550)(1350 6550);
FORCEPROP 2 LAST SIG_NAME CLK_100M_OCP_SFF_3_DP
J 0
(640 6560);
DISPLAY 0.510638 (640 6560);
PAINT WHITE (640 6560);
WIRE 16 -1 (275 6450)(1350 6450);
FORCEPROP 2 LAST SIG_NAME CLK_50M_NCSI_OCP_SFF_ISO
J 0
(640 6460);
DISPLAY 0.510638 (640 6460);
PAINT WHITE (640 6460);
WIRE 16 -1 (1850 6000)(3200 6000);
FORCEPROP 2 LAST SIG_NAME SMB_OCP_SFF_3V3AUX_BUF_SCL
J 0
(2440 6010);
DISPLAY 0.553191 (2440 6010);
PAINT WHITE (2440 6010);
WIRE 16 -1 (1850 5950)(3200 5950);
FORCEPROP 2 LAST SIG_NAME SMB_OCP_SFF_3V3AUX_BUF_SDA
J 0
(2440 5960);
DISPLAY 0.553191 (2440 5960);
PAINT WHITE (2440 5960);
WIRE 16 -1 (275 5900)(3200 5900);
FORCEPROP 2 LAST SIG_NAME RST_SMB_OCP_SFF_N
J 0
(640 5910);
DISPLAY 0.553191 (640 5910);
PAINT WHITE (640 5910);
WIRE 16 -1 (-2800 7050)(-1025 7050);
FORCEPROP 2 LAST SIG_NAME OCP_SFF_MAIN_PWR_EN_R
J 0
(-2235 7060);
DISPLAY 0.680851 (-2235 7060);
PAINT WHITE (-2235 7060);
WIRE 16 -1 (-4025 7100)(-1025 7100);
FORCEPROP 2 LAST SIG_NAME FM_OCP_SFF_PWR_GOOD
J 0
(-2235 7110);
DISPLAY 0.680851 (-2235 7110);
PAINT WHITE (-2235 7110);
WIRE 16 -1 (1350 7100)(275 7100);
FORCEPROP 2 LAST SIG_NAME RST_PERST2_OCP_SFF_N
J 0
(640 7110);
DISPLAY 0.553191 (640 7110);
PAINT WHITE (640 7110);
WIRE 16 -1 (1350 7050)(275 7050);
FORCEPROP 2 LAST SIG_NAME RST_PERST3_OCP_SFF_N
J 0
(640 7060);
DISPLAY 0.553191 (640 7060);
PAINT WHITE (640 7060);
WIRE 16 -1 (275 7000)(1350 7000);
FORCEPROP 2 LAST SIG_NAME IRQ_LVC3_OCP_SFF_WAKE_N
J 0
(640 7010);
DISPLAY 0.553191 (640 7010);
PAINT WHITE (640 7010);
WIRE 16 -1 (1650 5950)(275 5950);
FORCEPROP 2 LAST SIG_NAME SMB_OCP_SFF_3V3AUX_BUF_R_SDA
J 0
(640 5960);
DISPLAY 0.553191 (640 5960);
PAINT WHITE (640 5960);
WIRE 16 -1 (-3800 5850)(-1025 5850);
FORCEPROP 2 LAST SIG_NAME RST_PERST0_OCP_SFF_N
J 0
(-2185 5860);
DISPLAY 0.553191 (-2185 5860);
PAINT WHITE (-2185 5860);
WIRE 16 -1 (-3800 5750)(-3000 5750);
FORCEPROP 2 LAST SIG_NAME OCP_SFF_AUX_PWR_EN
J 0
(-3735 5760);
DISPLAY 0.553191 (-3735 5760);
PAINT WHITE (-3735 5760);
WIRE 16 -1 (-2950 4725)(-4150 4725);
FORCEPROP 0 LAST CDS_PHYS_NET_NAME OCP_SFF_AUX_PWR_EN
J 0
(-3785 4767);
PAINT MONO (-3785 4767);
DISPLAY INVISIBLE (-3785 4767);
FORCEPROP 2 LAST SIG_NAME OCP_SFF_AUX_PWR_EN
J 0
(-3710 4735);
DISPLAY 0.680851 (-3710 4735);
PAINT WHITE (-3710 4735);
WIRE 16 -1 (-3850 1825)(-3850 1950);
WIRE 16 -1 (-3850 1950)(-3300 1950);
FORCEPROP 2 LAST SIG_NAME OCP_SFF_ID1
J 0
(-3735 1960);
DISPLAY 0.680851 (-3735 1960);
PAINT WHITE (-3735 1960);
WIRE 16 -1 (-3850 2150)(-3850 1950);
WIRE 16 -1 (-4325 1825)(-4325 2000);
WIRE 16 -1 (-4325 2000)(-4325 2150);
WIRE 16 -1 (-4325 2000)(-3300 2000);
FORCEPROP 2 LAST SIG_NAME OCP_SFF_ID0
J 0
(-3735 2010);
DISPLAY 0.680851 (-3735 2010);
PAINT WHITE (-3735 2010);
WIRE 16 -1 (-4325 2450)(-4325 2350);
WIRE 16 -1 (-3850 2450)(-4325 2450);
WIRE 16 -1 (-3850 2350)(-3850 2450);
WIRE 16 -1 (275 2350)(550 2350);
WIRE 16 -1 (275 2400)(550 2400);
WIRE 16 -1 (550 2350)(550 2400);
WIRE 16 -1 (275 2450)(550 2450);
WIRE 16 -1 (550 2400)(550 2450);
WIRE 16 -1 (275 2500)(550 2500);
WIRE 16 -1 (550 2450)(550 2500);
WIRE 16 -1 (275 2550)(550 2550);
WIRE 16 -1 (550 2500)(550 2550);
WIRE 16 -1 (275 2800)(550 2800);
WIRE 16 -1 (550 2550)(550 2800);
WIRE 16 -1 (550 2950)(275 2950);
WIRE 16 -1 (550 2800)(550 2950);
WIRE 16 -1 (550 2950)(550 3100);
WIRE 16 -1 (550 3100)(275 3100);
WIRE 16 -1 (550 3250)(275 3250);
WIRE 16 -1 (550 3100)(550 3250);
WIRE 16 -1 (550 3400)(275 3400);
WIRE 16 -1 (550 3250)(550 3400);
WIRE 16 -1 (550 3550)(275 3550);
WIRE 16 -1 (550 3400)(550 3550);
WIRE 16 -1 (550 3700)(275 3700);
WIRE 16 -1 (550 3550)(550 3700);
WIRE 16 -1 (550 3850)(275 3850);
WIRE 16 -1 (550 3700)(550 3850);
WIRE 16 -1 (550 4000)(275 4000);
WIRE 16 -1 (550 3850)(550 4000);
WIRE 16 -1 (550 4200)(550 4000);
WIRE 16 -1 (550 4200)(275 4200);
WIRE 16 -1 (550 4350)(275 4350);
WIRE 16 -1 (550 4350)(550 4200);
WIRE 16 -1 (550 4500)(275 4500);
WIRE 16 -1 (550 4500)(550 4350);
WIRE 16 -1 (550 4650)(275 4650);
WIRE 16 -1 (550 4650)(550 4500);
WIRE 16 -1 (550 4800)(275 4800);
WIRE 16 -1 (550 4800)(550 4650);
WIRE 16 -1 (550 4950)(275 4950);
WIRE 16 -1 (550 4800)(550 4950);
WIRE 16 -1 (550 5100)(275 5100);
WIRE 16 -1 (550 5100)(550 4950);
WIRE 16 -1 (550 5100)(550 5250);
WIRE 16 -1 (550 5250)(275 5250);
WIRE 16 -1 (550 5400)(275 5400);
WIRE 16 -1 (550 5250)(550 5400);
WIRE 16 -1 (550 5550)(275 5550);
WIRE 16 -1 (550 5400)(550 5550);
WIRE 16 -1 (550 5700)(275 5700);
WIRE 16 -1 (550 5550)(550 5700);
WIRE 16 -1 (275 6050)(550 6050);
WIRE 16 -1 (550 6050)(550 5700);
WIRE 16 -1 (275 6100)(550 6100);
WIRE 16 -1 (550 6100)(550 6050);
WIRE 16 -1 (550 6150)(550 6100);
WIRE 16 -1 (275 6150)(550 6150);
WIRE 16 -1 (275 6200)(550 6200);
WIRE 16 -1 (550 6200)(550 6150);
WIRE 16 -1 (275 6250)(550 6250);
WIRE 16 -1 (550 6250)(550 6200);
WIRE 16 -1 (275 6300)(550 6300);
WIRE 16 -1 (550 6300)(550 6250);
WIRE 16 -1 (550 6650)(275 6650);
WIRE 16 -1 (275 6500)(550 6500);
WIRE 16 -1 (550 6500)(550 6300);
WIRE 16 -1 (550 6500)(550 6650);
WIRE 16 -1 (275 3300)(700 3300);
WIRE 16 -1 (850 3500)(275 3500);
WIRE 16 -1 (275 5000)(700 5000);
WIRE 16 -1 (1650 6000)(275 6000);
FORCEPROP 2 LAST SIG_NAME SMB_OCP_SFF_3V3AUX_BUF_R_SCL
J 0
(640 6010);
DISPLAY 0.553191 (640 6010);
PAINT WHITE (640 6010);
WIRE 16 -1 (275 4700)(700 4700);
WIRE 16 -1 (-1550 3000)(-1025 3000);
WIRE 16 -1 (275 4400)(700 4400);
WIRE 16 -1 (275 4550)(700 4550);
WIRE 16 -1 (275 5600)(1900 5600);
FORCEPROP 2 LAST SIG_NAME CLK_100M_OCP_SFF_1_DP
J 0
(640 5610);
DISPLAY 0.510638 (640 5610);
PAINT WHITE (640 5610);
WIRE 16 -1 (-4350 4625)(-4675 4625);
WIRE 16 -1 (-4675 4725)(-4675 4625);
WIRE 16 -1 (-4675 4725)(-4350 4725);
WIRE 16 -1 (2825 1800)(2825 1675);
WIRE 16 -1 (2825 1675)(3075 1675);
WIRE 16 -1 (3075 1675)(3075 1800);
WIRE 16 -1 (3350 1675)(3075 1675);
WIRE 16 -1 (3350 1675)(3350 1800);
WIRE 16 -1 (3625 1675)(3350 1675);
WIRE 16 -1 (3625 1675)(3625 1800);
WIRE 16 -1 (-1550 3200)(-1025 3200);
FORCEPROP 0 LAST $PNN P5E_CPU0_PE1_TX_C_DN<13>
J 0
(-1287 3200);
DISPLAY INVISIBLE (-1287 3200);
WIRE 16 -1 (275 4600)(850 4600);
WIRE 16 -1 (275 4450)(850 4450);
WIRE 16 -1 (275 3450)(700 3450);
WIRE 16 -1 (275 2700)(1400 2700);
FORCEPROP 2 LAST SIG_NAME OCP_SFF_USB2_3_DP
J 0
(590 2710);
DISPLAY 0.638298 (590 2710);
PAINT WHITE (590 2710);
WIRE 16 -1 (275 2650)(1100 2650);
FORCEPROP 2 LAST SIG_NAME OCP_SFF_PWRBRK_N
J 0
(590 2660);
DISPLAY 0.638298 (590 2660);
PAINT WHITE (590 2660);
WIRE 16 -1 (2825 2125)(2825 2000);
WIRE 16 -1 (3075 2125)(3075 2000);
WIRE 16 -1 (2825 2125)(3075 2125);
WIRE 16 -1 (3625 2125)(3625 2000);
WIRE 16 -1 (3350 2125)(3350 2000);
WIRE 16 -1 (3075 2125)(3350 2125);
WIRE 16 -1 (3350 2125)(3625 2125);
WIRE 16 -1 (2300 1525)(2300 1650);
WIRE 16 -1 (2025 1525)(2025 1650);
WIRE 16 -1 (2300 1525)(2025 1525);
WIRE 16 -1 (2025 1525)(1750 1525);
WIRE 16 -1 (1750 1525)(1750 1650);
WIRE 16 -1 (1475 1525)(1475 1650);
WIRE 16 -1 (1475 1525)(1750 1525);
WIRE 16 -1 (1475 1525)(1075 1525);
WIRE 16 -1 (1075 1525)(1075 1650);
WIRE 16 -1 (800 1525)(1075 1525);
WIRE 16 -1 (800 1650)(800 1525);
WIRE 16 -1 (275 3350)(850 3350);
WIRE 16 -1 (275 3150)(700 3150);
WIRE 16 -1 (275 3600)(700 3600);
WIRE 16 -1 (275 3650)(850 3650);
WIRE 16 -1 (275 3750)(700 3750);
WIRE 16 -1 (275 3800)(850 3800);
WIRE 16 -1 (275 3900)(700 3900);
WIRE 16 -1 (850 3950)(275 3950);
WIRE 16 -1 (275 4250)(700 4250);
WIRE 16 -1 (275 4300)(850 4300);
WIRE 16 -1 (275 5300)(700 5300);
WIRE 16 -1 (275 5350)(850 5350);
WIRE 16 -1 (850 5050)(275 5050);
WIRE 16 -1 (275 3200)(850 3200);
WIRE 16 -1 (275 5500)(700 5500);
WIRE 16 -1 (275 5450)(850 5450);
WIRE 16 -1 (-1550 4600)(-1025 4600);
WIRE 16 -1 (-1550 3300)(-1025 3300);
WIRE 16 -1 (-1700 3350)(-1025 3350);
WIRE 16 -1 (275 3050)(850 3050);
WIRE 16 -1 (275 3000)(700 3000);
WIRE 16 -1 (275 2750)(1400 2750);
FORCEPROP 2 LAST SIG_NAME OCP_SFF_USB2_3_DN
J 0
(590 2760);
DISPLAY 0.638298 (590 2760);
PAINT WHITE (590 2760);
WIRE 16 -1 (275 2850)(700 2850);
WIRE 16 -1 (275 2900)(850 2900);
WIRE 16 -1 (-1550 3800)(-1025 3800);
WIRE 16 -1 (-1700 3650)(-1025 3650);
WIRE 16 -1 (-1550 3600)(-1025 3600);
WIRE 16 -1 (-1550 3500)(-1025 3500);
WIRE 16 -1 (-1700 3150)(-1025 3150);
WIRE 16 -1 (-1700 3450)(-1025 3450);
WIRE 16 -1 (-1700 3050)(-1025 3050);
WIRE 16 -1 (-1550 2900)(-1025 2900);
FORCEPROP 0 LAST $PNN P5E_CPU0_PE1_TX_C_DN<15>
J 0
(-1287 2900);
DISPLAY INVISIBLE (-1287 2900);
WIRE 16 -1 (800 1850)(800 1975);
WIRE 16 -1 (800 1975)(1075 1975);
WIRE 16 -1 (1075 1975)(1075 1850);
WIRE 16 -1 (1475 1975)(1075 1975);
WIRE 16 -1 (1475 1975)(1475 1850);
WIRE 16 -1 (1475 1975)(1750 1975);
WIRE 16 -1 (1750 1975)(1750 1850);
WIRE 16 -1 (1750 1975)(2025 1975);
WIRE 16 -1 (2025 1975)(2025 1850);
WIRE 16 -1 (2025 1975)(2300 1975);
WIRE 16 -1 (2300 1975)(2300 1850);
WIRE 16 -1 (-2750 2700)(-1025 2700);
FORCEPROP 2 LAST SIG_NAME TP_OCP_SFF_B69
J 0
(-2685 2710);
DISPLAY 0.680851 (-2685 2710);
PAINT WHITE (-2685 2710);
WIRE 16 -1 (-2750 2750)(-1025 2750);
FORCEPROP 2 LAST SIG_NAME TP_OCP_SFF_B68
J 0
(-2685 2760);
DISPLAY 0.680851 (-2685 2760);
PAINT WHITE (-2685 2760);
WIRE 16 -1 (-1025 2850)(-1700 2850);
WIRE 16 -1 (2500 2700)(1600 2700);
FORCEPROP 2 LAST SIG_NAME USB2_3_DP
J 0
(2065 2710);
DISPLAY 0.638298 (2065 2710);
PAINT WHITE (2065 2710);
WIRE 16 -1 (1600 2750)(2500 2750);
FORCEPROP 2 LAST SIG_NAME USB2_3_DN
J 0
(2065 2760);
DISPLAY 0.638298 (2065 2760);
PAINT WHITE (2065 2760);
WIRE 16 -1 (275 4150)(1900 4150);
FORCEPROP 2 LAST SIG_NAME OCP_SFF_PRSNT1_R_N
J 0
(990 4160);
DISPLAY 0.638298 (990 4160);
PAINT WHITE (990 4160);
WIRE 16 -1 (275 5650)(1900 5650);
FORCEPROP 2 LAST SIG_NAME CLK_100M_OCP_SFF_1_DN
J 0
(640 5660);
DISPLAY 0.510638 (640 5660);
PAINT WHITE (640 5660);
WIRE 16 -1 (275 5750)(1900 5750);
FORCEPROP 2 LAST SIG_NAME OCP_SFF_PRSNT2_R_N
J 0
(640 5760);
DISPLAY 0.510638 (640 5760);
PAINT WHITE (640 5760);
WIRE 16 -1 (1900 5800)(275 5800);
FORCEPROP 2 LAST SIG_NAME RST_PERST1_OCP_SFF_N
J 0
(640 5810);
DISPLAY 0.553191 (640 5810);
PAINT WHITE (640 5810);
WIRE 16 -1 (3100 5850)(275 5850);
FORCEPROP 2 LAST SIG_NAME OCP_SFF_PRSNTA_R_N
J 0
(640 5860);
DISPLAY 0.510638 (640 5860);
PAINT WHITE (640 5860);
WIRE 16 -1 (3100 5700)(3100 5850);
WIRE 16 -1 (275 6750)(1350 6750);
FORCEPROP 2 LAST SIG_NAME NCSI_OCP_SFF_TXD1
J 0
(640 6760);
DISPLAY 0.553191 (640 6760);
PAINT WHITE (640 6760);
WIRE 16 -1 (-1700 3950)(-1025 3950);
WIRE 16 -1 (-1550 3900)(-1025 3900);
WIRE 16 -1 (-1700 3750)(-1025 3750);
WIRE 16 -1 (-2750 2650)(-1025 2650);
FORCEPROP 2 LAST SIG_NAME OCP_SFF_PRSNT3_R_N
J 0
(-2685 2660);
DISPLAY 0.680851 (-2685 2660);
PAINT WHITE (-2685 2660);
WIRE 16 -1 (-1975 1800)(-875 1800);
FORCEPROP 2 LAST SIG_NAME SGPIO_OCP_SFF_DATAIN
J 0
(-1860 1810);
DISPLAY 0.680851 (-1860 1810);
PAINT WHITE (-1860 1810);
WIRE 16 -1 (-1975 1975)(-875 1975);
FORCEPROP 2 LAST SIG_NAME SGPIO_OCP_SFF_LD_N
J 0
(-1860 1985);
DISPLAY 0.680851 (-1860 1985);
PAINT WHITE (-1860 1985);
WIRE 16 -1 (-1700 4450)(-1025 4450);
WIRE 16 -1 (-1700 5200)(-1025 5200);
WIRE 16 -1 (-1700 5300)(-1025 5300);
WIRE 16 -1 (-1550 5150)(-1025 5150);
WIRE 16 -1 (-1550 5050)(-1025 5050);
WIRE 16 -1 (-1700 5000)(-1025 5000);
WIRE 16 -1 (-1550 4700)(-1025 4700);
WIRE 16 -1 (-1700 4550)(-1025 4550);
WIRE 16 -1 (-1550 4400)(-1025 4400);
WIRE 16 -1 (-1550 4300)(-1025 4300);
WIRE 16 -1 (-1025 4150)(-2750 4150);
FORCEPROP 2 LAST SIG_NAME OCP_SFF_PRSNT0_R_N
J 0
(-2685 4160);
DISPLAY 0.680851 (-2685 4160);
PAINT WHITE (-2685 4160);
WIRE 16 -1 (-1700 4250)(-1025 4250);
WIRE 16 -1 (275 4750)(850 4750);
WIRE 16 -1 (-1700 4750)(-1025 4750);
WIRE 16 -1 (-1550 5350)(-1025 5350);
WIRE 16 -1 (-1700 5450)(-1025 5450);
WIRE 16 -1 (-1550 5500)(-1025 5500);
WIRE 16 -1 (275 6950)(1350 6950);
FORCEPROP 2 LAST SIG_NAME OCP_SFF_ISO1_RBT_ARB_IN
J 0
(640 6960);
DISPLAY 0.553191 (640 6960);
PAINT WHITE (640 6960);
WIRE 16 -1 (275 6850)(1350 6850);
FORCEPROP 2 LAST SIG_NAME OCP_SFF_ID1
J 0
(640 6860);
DISPLAY 0.553191 (640 6860);
PAINT WHITE (640 6860);
WIRE 16 -1 (275 6800)(1350 6800);
FORCEPROP 2 LAST SIG_NAME NCSI_OCP_SFF_TX_EN
J 0
(640 6810);
DISPLAY 0.553191 (640 6810);
PAINT WHITE (640 6810);
WIRE 16 -1 (275 6700)(1350 6700);
FORCEPROP 2 LAST SIG_NAME NCSI_OCP_SFF_TXD0
J 0
(640 6710);
DISPLAY 0.553191 (640 6710);
PAINT WHITE (640 6710);
WIRE 16 -1 (275 6900)(1350 6900);
FORCEPROP 2 LAST SIG_NAME OCP_SFF_ISO2_RBT_ARB_OUT
J 0
(640 6910);
DISPLAY 0.553191 (640 6910);
PAINT WHITE (640 6910);
WIRE 16 -1 (275 5150)(700 5150);
WIRE 16 -1 (275 5200)(850 5200);
WIRE 16 -1 (-1375 6650)(-1025 6650);
WIRE 16 -1 (-1375 6500)(-1375 6650);
WIRE 16 -1 (-1375 6500)(-1025 6500);
WIRE 16 -1 (-1375 5700)(-1025 5700);
WIRE 16 -1 (-1375 6500)(-1375 5700);
WIRE 16 -1 (-1375 5550)(-1025 5550);
WIRE 16 -1 (-1375 5550)(-1375 5700);
WIRE 16 -1 (-1375 5400)(-1375 5550);
WIRE 16 -1 (-1375 5400)(-1025 5400);
WIRE 16 -1 (-1375 5400)(-1375 5250);
WIRE 16 -1 (-1375 5250)(-1025 5250);
WIRE 16 -1 (-1375 5100)(-1025 5100);
WIRE 16 -1 (-1375 5250)(-1375 5100);
WIRE 16 -1 (-1375 5100)(-1375 4950);
WIRE 16 -1 (-1375 4950)(-1025 4950);
WIRE 16 -1 (-1375 4800)(-1375 4950);
WIRE 16 -1 (-1375 4800)(-1025 4800);
WIRE 16 -1 (-1375 4650)(-1375 4800);
WIRE 16 -1 (-1375 4650)(-1025 4650);
WIRE 16 -1 (-1375 4500)(-1025 4500);
WIRE 16 -1 (-1375 4500)(-1375 4650);
WIRE 16 -1 (-1375 4500)(-1375 4350);
WIRE 16 -1 (-1375 4350)(-1025 4350);
WIRE 16 -1 (-1375 4200)(-1375 4350);
WIRE 16 -1 (-1375 4200)(-1025 4200);
WIRE 16 -1 (-1375 4000)(-1025 4000);
WIRE 16 -1 (-1375 4200)(-1375 4000);
WIRE 16 -1 (-1375 3850)(-1375 4000);
WIRE 16 -1 (-1375 3850)(-1025 3850);
WIRE 16 -1 (-1375 3700)(-1375 3850);
WIRE 16 -1 (-1375 3700)(-1025 3700);
WIRE 16 -1 (-1375 3550)(-1025 3550);
WIRE 16 -1 (-1375 3550)(-1375 3700);
WIRE 16 -1 (-1375 3400)(-1375 3550);
WIRE 16 -1 (-1375 3400)(-1025 3400);
WIRE 16 -1 (-1375 3400)(-1375 3250);
WIRE 16 -1 (-1375 3250)(-1025 3250);
WIRE 16 -1 (-1375 3250)(-1375 3100);
WIRE 16 -1 (-1375 3100)(-1025 3100);
WIRE 16 -1 (-1375 2950)(-1025 2950);
WIRE 16 -1 (-1375 3100)(-1375 2950);
WIRE 16 -1 (-1375 2950)(-1375 2800);
WIRE 16 -1 (-1375 2800)(-1025 2800);
WIRE 16 -1 (-3800 6000)(-3000 6000);
FORCEPROP 2 LAST SIG_NAME OCP_SFF_ISO_BIF0_EN
J 0
(-3735 6010);
DISPLAY 0.553191 (-3735 6010);
PAINT WHITE (-3735 6010);
WIRE 16 -1 (-2750 5650)(-1025 5650);
FORCEPROP 2 LAST SIG_NAME CLK_100M_OCP_SFF_0_DN
J 0
(-2685 5660);
DISPLAY 0.680851 (-2685 5660);
PAINT WHITE (-2685 5660);
WIRE 16 -1 (-3800 5950)(-3000 5950);
FORCEPROP 2 LAST SIG_NAME OCP_SFF_ISO_BIF1_EN
J 0
(-3735 5960);
DISPLAY 0.553191 (-3735 5960);
PAINT WHITE (-3735 5960);
WIRE 16 -1 (-3800 5900)(-3000 5900);
FORCEPROP 2 LAST SIG_NAME OCP_SFF_ISO_BIF2_EN
J 0
(-3735 5910);
DISPLAY 0.553191 (-3735 5910);
PAINT WHITE (-3735 5910);
WIRE 16 -1 (-2750 5600)(-1025 5600);
FORCEPROP 2 LAST SIG_NAME CLK_100M_OCP_SFF_0_DP
J 0
(-2685 5610);
DISPLAY 0.680851 (-2685 5610);
PAINT WHITE (-2685 5610);
WIRE 16 -1 (-2800 5950)(-1025 5950);
FORCEPROP 2 LAST SIG_NAME OCP_SFF_BIF1_R_N
J 0
(-2185 5960);
DISPLAY 0.553191 (-2185 5960);
PAINT WHITE (-2185 5960);
WIRE 16 -1 (-2275 5800)(-1025 5800);
WIRE 16 -1 (-2800 5900)(-1025 5900);
FORCEPROP 2 LAST SIG_NAME OCP_SFF_BIF2_R_N
J 0
(-2185 5910);
DISPLAY 0.553191 (-2185 5910);
PAINT WHITE (-2185 5910);
WIRE 16 -1 (-2950 4425)(-4150 4425);
FORCEPROP 0 LAST CDS_PHYS_NET_NAME FM_OCP_SFF_PWR_GOOD
J 0
(-3785 4467);
PAINT MONO (-3785 4467);
DISPLAY INVISIBLE (-3785 4467);
FORCEPROP 2 LAST SIG_NAME FM_OCP_SFF_PWR_GOOD
J 0
(-3710 4435);
DISPLAY 0.680851 (-3710 4435);
PAINT WHITE (-3710 4435);
WIRE 16 -1 (-1025 5750)(-2800 5750);
FORCEPROP 2 LAST SIG_NAME OCP_SFF_AUX_PWR_EN_R
J 0
(-2185 5760);
DISPLAY 0.553191 (-2185 5760);
PAINT WHITE (-2185 5760);
WIRE 16 -1 (-2300 6750)(-1025 6750);
FORCEPROP 2 LAST SIG_NAME NCSI_OCP_SFF_RXD1
J 0
(-2235 6760);
DISPLAY 0.680851 (-2235 6760);
PAINT WHITE (-2235 6760);
WIRE 16 -1 (-2300 6700)(-1025 6700);
FORCEPROP 2 LAST SIG_NAME NCSI_OCP_SFF_RXD0
J 0
(-2235 6710);
DISPLAY 0.680851 (-2235 6710);
PAINT WHITE (-2235 6710);
WIRE 16 -1 (-2300 6600)(-1025 6600);
FORCEPROP 2 LAST SIG_NAME CLK_100M_OCP_SFF_2_DN
J 0
(-2235 6610);
DISPLAY 0.680851 (-2235 6610);
PAINT WHITE (-2235 6610);
WIRE 16 -1 (-2300 6550)(-1025 6550);
FORCEPROP 2 LAST SIG_NAME CLK_100M_OCP_SFF_2_DP
J 0
(-2235 6560);
DISPLAY 0.680851 (-2235 6560);
PAINT WHITE (-2235 6560);
WIRE 16 -1 (-1025 6450)(-2300 6450);
FORCEPROP 2 LAST SIG_NAME NCSI_OCP_SFF_CRS_DV
J 0
(-2235 6460);
DISPLAY 0.680851 (-2235 6460);
PAINT WHITE (-2235 6460);
WIRE 16 -1 (-2300 6800)(-1025 6800);
FORCEPROP 2 LAST SIG_NAME OCP_SFF_ID0
J 0
(-2235 6810);
DISPLAY 0.680851 (-2235 6810);
PAINT WHITE (-2235 6810);
WIRE 16 -1 (-1450 6050)(-1025 6050);
WIRE 16 -1 (-1450 6050)(-1450 6100);
WIRE 16 -1 (-1025 6100)(-1450 6100);
WIRE 16 -1 (-1450 6100)(-1450 6150);
WIRE 16 -1 (-1025 6150)(-1450 6150);
WIRE 16 -1 (-1450 6150)(-1450 6200);
WIRE 16 -1 (-1025 6200)(-1450 6200);
WIRE 16 -1 (-1450 6200)(-1450 6250);
WIRE 16 -1 (-1025 6250)(-1450 6250);
WIRE 16 -1 (-1450 6250)(-1450 6300);
WIRE 16 -1 (-1025 6300)(-1450 6300);
WIRE 16 -1 (-2300 6850)(-1025 6850);
FORCEPROP 2 LAST SIG_NAME SGPIO_OCP_SFF_CLK
J 0
(-2235 6860);
DISPLAY 0.680851 (-2235 6860);
PAINT WHITE (-2235 6860);
WIRE 16 -1 (-2300 6900)(-1025 6900);
FORCEPROP 2 LAST SIG_NAME SGPIO_OCP_SFF_DATAOUT
J 0
(-2235 6910);
DISPLAY 0.680851 (-2235 6910);
PAINT WHITE (-2235 6910);
WIRE 16 -1 (-2300 6950)(-1025 6950);
FORCEPROP 2 LAST SIG_NAME SGPIO_OCP_SFF_DATAIN
J 0
(-2235 6960);
DISPLAY 0.680851 (-2235 6960);
PAINT WHITE (-2235 6960);
WIRE 16 -1 (-2300 7000)(-1025 7000);
FORCEPROP 2 LAST SIG_NAME SGPIO_OCP_SFF_LD_N
J 0
(-2235 7010);
DISPLAY 0.680851 (-2235 7010);
PAINT WHITE (-2235 7010);
WIRE 16 -1 (-3000 7050)(-4025 7050);
FORCEPROP 2 LAST SIG_NAME OCP_SFF_MAIN_PWR_EN
J 0
(-3960 7060);
DISPLAY 0.553191 (-3960 7060);
PAINT WHITE (-3960 7060);
WIRE 16 -1 (-2950 4625)(-4150 4625);
FORCEPROP 0 LAST CDS_PHYS_NET_NAME OCP_SFF_MAIN_PWR_EN
J 0
(-3785 4667);
PAINT MONO (-3785 4667);
DISPLAY INVISIBLE (-3785 4667);
FORCEPROP 2 LAST SIG_NAME OCP_SFF_MAIN_PWR_EN
J 0
(-3710 4635);
DISPLAY 0.680851 (-3710 4635);
PAINT WHITE (-3710 4635);
WIRE 16 -1 (-2800 6000)(-1025 6000);
FORCEPROP 2 LAST SIG_NAME OCP_SFF_BIF0_R_N
J 0
(-2185 6010);
DISPLAY 0.553191 (-2185 6010);
PAINT WHITE (-2185 6010);
WIRE 16 -1 (-675 1975)(-225 1975);
WIRE 16 -1 (-675 1800)(-225 1800);
WIRE 16 -1 (-225 1800)(-225 1975);
WIRE 16 -1 (-225 1800)(-225 1625);
WIRE 16 -1 (-675 1625)(-225 1625);
WIRE 16 -1 (-1950 1450)(-875 1450);
FORCEPROP 2 LAST SIG_NAME SGPIO_OCP_SFF_DATAOUT
J 0
(-1835 1460);
DISPLAY 0.680851 (-1835 1460);
PAINT WHITE (-1835 1460);
WIRE 16 -1 (-675 1450)(-225 1450);
WIRE 16 -1 (-1975 1625)(-875 1625);
FORCEPROP 2 LAST SIG_NAME SGPIO_OCP_SFF_CLK
J 0
(-1860 1635);
DISPLAY 0.680851 (-1860 1635);
PAINT WHITE (-1860 1635);
DOT 1 (550 6250);
DOT 1 (550 6200);
DOT 1 (-1450 6200);
DOT 1 (-1375 4200);
DOT 1 (-1375 5250);
DOT 1 (-1375 5400);
DOT 1 (-1375 4650);
DOT 1 (550 2500);
DOT 1 (550 2550);
DOT 1 (-1375 3100);
DOT 1 (-1375 4950);
DOT 1 (550 5550);
DOT 1 (3075 1675);
DOT 1 (3350 1675);
DOT 1 (3625 1675);
DOT 1 (2825 2125);
DOT 1 (3075 2125);
DOT 1 (3350 2125);
DOT 1 (-225 1975);
DOT 1 (-4325 2000);
DOT 1 (-3850 1950);
DOT 1 (-4325 2450);
DOT 1 (-4675 4625);
DOT 1 (-4675 4425);
DOT 1 (-1375 5700);
DOT 1 (-1450 6150);
DOT 1 (-1450 6250);
DOT 1 (-1450 6300);
DOT 1 (-1375 4800);
DOT 1 (-1375 2800);
DOT 1 (-1375 2950);
DOT 1 (-1375 3550);
DOT 1 (-1375 3700);
DOT 1 (-1375 3850);
DOT 1 (-1375 3400);
DOT 1 (550 2800);
DOT 1 (550 3250);
DOT 1 (550 3550);
DOT 1 (550 3400);
DOT 1 (550 3700);
DOT 1 (550 3850);
DOT 1 (550 4000);
DOT 1 (550 4350);
DOT 1 (550 4200);
DOT 1 (550 4500);
DOT 1 (550 4650);
DOT 1 (550 4800);
DOT 1 (550 5100);
DOT 1 (550 4950);
DOT 1 (550 5250);
DOT 1 (550 5400);
DOT 1 (550 6050);
DOT 1 (550 6100);
DOT 1 (550 6150);
DOT 1 (550 6300);
DOT 1 (550 6500);
DOT 1 (-1375 5100);
DOT 1 (-1375 4000);
DOT 1 (-1375 3250);
DOT 1 (550 2950);
DOT 1 (550 3100);
DOT 1 (550 2350);
DOT 1 (2025 1975);
DOT 1 (1750 1975);
DOT 1 (1475 1975);
DOT 1 (1075 1975);
DOT 1 (800 1975);
DOT 1 (2025 1525);
DOT 1 (1750 1525);
DOT 1 (1475 1525);
DOT 1 (1075 1525);
DOT 1 (2300 1525);
DOT 1 (-1375 4500);
DOT 1 (550 2400);
DOT 1 (550 2450);
DOT 1 (-1375 6500);
DOT 1 (-1375 4350);
DOT 1 (-1375 5550);
DOT 1 (550 5700);
DOT 1 (-1450 6100);
DOT 1 (-225 1800);
FORCENOTE
20230414 CHANGE R425 TO 200 OHM
(1150 6175) 0;
DISPLAY LEFT (1150 6175);
DISPLAY 0.808511 (1150 6175);
PAINT PINK (1150 6175);
FORCENOTE
20210525 MODIFY FOR GT
(-4725 7425) 0;
DISPLAY LEFT (-4725 7425);
DISPLAY 2.510638 (-4725 7425);
PAINT PINK (-4725 7425);
FORCENOTE
FROM CPU0 PCIE PORT1 [15:0]
(-4600 5250) 0;
DISPLAY LEFT (-4600 5250);
DISPLAY 1.276596 (-4600 5250);
PAINT SKYBLUE (-4600 5250);
FORCENOTE
FRU ADDRESS:0X50
(-4525 1300) 0;
DISPLAY LEFT (-4525 1300);
DISPLAY 1.595745 (-4525 1300);
PAINT WHITE (-4525 1300);
FORCENOTE
DP/DN SWAP
(-2325 4425) 0;
DISPLAY LEFT (-2325 4425);
DISPLAY 1.021277 (-2325 4425);
FORCENOTE
DP/DN SWAP
(1025 3750) 0;
DISPLAY LEFT (1025 3750);
DISPLAY 1.021277 (1025 3750);
FORCENOTE
DP/DN SWAP
(1025 3900) 0;
DISPLAY LEFT (1025 3900);
DISPLAY 1.021277 (1025 3900);
FORCENOTE
DP/DN SWAP
(1025 3600) 0;
DISPLAY LEFT (1025 3600);
DISPLAY 1.021277 (1025 3600);
FORCENOTE
DP/DN SWAP
(1025 3450) 0;
DISPLAY LEFT (1025 3450);
DISPLAY 1.021277 (1025 3450);
FORCENOTE
DP/DN SWAP
(1025 3025) 0;
DISPLAY LEFT (1025 3025);
DISPLAY 1.021277 (1025 3025);
FORCENOTE
DP/DN SWAP
(1025 3325) 0;
DISPLAY LEFT (1025 3325);
DISPLAY 1.021277 (1025 3325);
FORCENOTE
DP/DN SWAP
(1025 3175) 0;
DISPLAY LEFT (1025 3175);
DISPLAY 1.021277 (1025 3175);
FORCENOTE
DP/DN SWAP
(1000 4275) 0;
DISPLAY LEFT (1000 4275);
DISPLAY 1.021277 (1000 4275);
FORCENOTE
DP/DN SWAP
(1000 4425) 0;
DISPLAY LEFT (1000 4425);
DISPLAY 1.021277 (1000 4425);
FORCENOTE
DP/DN SWAP
(1000 4575) 0;
DISPLAY LEFT (1000 4575);
DISPLAY 1.021277 (1000 4575);
FORCENOTE
DP/DN SWAP
(1000 4725) 0;
DISPLAY LEFT (1000 4725);
DISPLAY 1.021277 (1000 4725);
FORCENOTE
TO CPU0 PCIE PORT1 [15:0]
(1850 5200) 0;
DISPLAY LEFT (1850 5200);
DISPLAY 1.276596 (1850 5200);
PAINT SKYBLUE (1850 5200);
FORCENOTE
DP/DN SWAP
(-2300 3925) 0;
DISPLAY LEFT (-2300 3925);
DISPLAY 1.021277 (-2300 3925);
FORCENOTE
DP/DN SWAP
(-2300 3325) 0;
DISPLAY LEFT (-2300 3325);
DISPLAY 1.021277 (-2300 3325);
FORCENOTE
DP/DN SWAP
(-2300 3025) 0;
DISPLAY LEFT (-2300 3025);
DISPLAY 1.021277 (-2300 3025);
FORCENOTE
DP/DN SWAP
(1025 2875) 0;
DISPLAY LEFT (1025 2875);
DISPLAY 1.021277 (1025 2875);
FORCENOTE
DP/DN SWAP
(1000 5025) 0;
DISPLAY LEFT (1000 5025);
DISPLAY 1.021277 (1000 5025);
FORCENOTE
DP/DN SWAP
(1000 5175) 0;
DISPLAY LEFT (1000 5175);
DISPLAY 1.021277 (1000 5175);
FORCENOTE
DP/DN SWAP
(1000 5325) 0;
DISPLAY LEFT (1000 5325);
DISPLAY 1.021277 (1000 5325);
FORCENOTE
DP/DN SWAP
(-2300 3625) 0;
DISPLAY LEFT (-2300 3625);
DISPLAY 1.021277 (-2300 3625);
FORCENOTE
DP/DN SWAP
(-2325 5150) 0;
DISPLAY LEFT (-2325 5150);
DISPLAY 1.021277 (-2325 5150);
FORCENOTE
DP/DN SWAP
(-2325 4725) 0;
DISPLAY LEFT (-2325 4725);
DISPLAY 1.021277 (-2325 4725);
FORCENOTE
$CDS_IMAGE|clipboard_0_10.jpg|2416|531
(-3675 3125) 0;
DISPLAY LEFT (-3675 3125);
QUIT
